G04 ================== begin FILE IDENTIFICATION RECORD ==================*
G04 Layout Name:  9048_F0T_Management_Board_D_brd_V04_1213_1625.brd*
G04 Film Name:    vcc*
G04 File Format:  Gerber RS274X*
G04 File Origin:  Cadence Allegro 17.2-S081*
G04 Origin Date:  Tue Dec 13 16:31:10 2022*
G04 *
G04 Layer:  DRAWING FORMAT/TITLE_BLOCK_A*
G04 Layer:  DRAWING FORMAT/TITLE_BLOCK*
G04 Layer:  VIA CLASS/VCC*
G04 Layer:  PIN/VCC*
G04 Layer:  MANUFACTURING/PHOTOPLOT_OUTLINE*
G04 Layer:  ETCH/VCC*
G04 Layer:  DRAWING FORMAT/TITLE_DATA_VCC*
G04 *
G04 Offset:    (0.00 0.00)*
G04 Mirror:    No*
G04 Mode:      Negative*
G04 Rotation:  0*
G04 FullContactRelief:  No*
G04 UndefLineWidth:     6.00*
G04 ================== end FILE IDENTIFICATION RECORD ====================*
%FSLAX25Y25*MOIN*%
%IR0*IPPOS*OFA0.00000B0.00000*MIA0B0*SFA1.00000B1.00000*%
%ADD14C,.03*%
%ADD23C,.052*%
%ADD22C,.061*%
%ADD35C,.071*%
%ADD26C,.026*%
%AMMACRO32*
4,1,36,.0025,0.0,
.002462,.000434,
.002349,.000855,
.002165,.00125,
.001915,.001607,
.001607,.001915,
.00125,.002165,
.000855,.002349,
.000434,.002462,
0.0,.0025,
-.000434,.002462,
-.000855,.002349,
-.00125,.002165,
-.001607,.001915,
-.001915,.001607,
-.002165,.00125,
-.002349,.000855,
-.002462,.000434,
-.0025,0.0,
-.002462,-.000434,
-.002349,-.000855,
-.002165,-.00125,
-.001915,-.001607,
-.001607,-.001915,
-.00125,-.002165,
-.000855,-.002349,
-.000434,-.002462,
0.0,-.0025,
.000434,-.002462,
.000855,-.002349,
.00125,-.002165,
.001607,-.001915,
.001915,-.001607,
.002165,-.00125,
.002349,-.000855,
.002462,-.000434,
.0025,0.0,
180.*
%
%ADD32MACRO32*%
%AMMACRO21*
4,1,36,.0025,0.0,
.002462,.000434,
.002349,.000855,
.002165,.00125,
.001915,.001607,
.001607,.001915,
.00125,.002165,
.000855,.002349,
.000434,.002462,
0.0,.0025,
-.000434,.002462,
-.000855,.002349,
-.00125,.002165,
-.001607,.001915,
-.001915,.001607,
-.002165,.00125,
-.002349,.000855,
-.002462,.000434,
-.0025,0.0,
-.002462,-.000434,
-.002349,-.000855,
-.002165,-.00125,
-.001915,-.001607,
-.001607,-.001915,
-.00125,-.002165,
-.000855,-.002349,
-.000434,-.002462,
0.0,-.0025,
.000434,-.002462,
.000855,-.002349,
.00125,-.002165,
.001607,-.001915,
.001915,-.001607,
.002165,-.00125,
.002349,-.000855,
.002462,-.000434,
.0025,0.0,
270.*
%
%ADD21MACRO21*%
%AMMACRO37*
4,1,36,.003,0.0,
.002954,.000521,
.002819,.001026,
.002598,.0015,
.002298,.001928,
.001928,.002298,
.0015,.002598,
.001026,.002819,
.000521,.002954,
0.0,.003,
-.000521,.002954,
-.001026,.002819,
-.0015,.002598,
-.001928,.002298,
-.002298,.001928,
-.002598,.0015,
-.002819,.001026,
-.002954,.000521,
-.003,0.0,
-.002954,-.000521,
-.002819,-.001026,
-.002598,-.0015,
-.002298,-.001928,
-.001928,-.002298,
-.0015,-.002598,
-.001026,-.002819,
-.000521,-.002954,
0.0,-.003,
.000521,-.002954,
.001026,-.002819,
.0015,-.002598,
.001928,-.002298,
.002298,-.001928,
.002598,-.0015,
.002819,-.001026,
.002954,-.000521,
.003,0.0,
270.*
%
%ADD37MACRO37*%
%AMMACRO40*
4,1,36,-.003,0.0,
-.002954,.000521,
-.002819,.001026,
-.002598,.0015,
-.002298,.001928,
-.001928,.002298,
-.0015,.002598,
-.001026,.002819,
-.000521,.002954,
0.0,.003,
.000521,.002954,
.001026,.002819,
.0015,.002598,
.001928,.002298,
.002298,.001928,
.002598,.0015,
.002819,.001026,
.002954,.000521,
.003,0.0,
.002954,-.000521,
.002819,-.001026,
.002598,-.0015,
.002298,-.001928,
.001928,-.002298,
.0015,-.002598,
.001026,-.002819,
.000521,-.002954,
0.0,-.003,
-.000521,-.002954,
-.001026,-.002819,
-.0015,-.002598,
-.001928,-.002298,
-.002298,-.001928,
-.002598,-.0015,
-.002819,-.001026,
-.002954,-.000521,
-.003,0.0,
270.*
%
%ADD40MACRO40*%
%ADD36C,.0435*%
%ADD30C,.048*%
%ADD15C,.066*%
%ADD25C,.078*%
%ADD11C,.087*%
%ADD31C,.097*%
%AMMACRO24*
4,1,15,.02475,.01414,
.026829,.009627,
.028094,.004822,
.028504,-.000129,
.028049,-.005077,
.026741,-.009871,
.02475,-.01414,
.02984,-.01923,
.032726,-.013756,
.034617,-.007864,
.035457,-.001734,
.03522,.00445,
.033912,.010498,
.031574,.016227,
.02984,.01923,
.02475,.01414,
0.0*
4,1,15,.01414,-.02475,
.009627,-.026829,
.004822,-.028094,
-.000129,-.028504,
-.005077,-.028049,
-.009871,-.026741,
-.01414,-.02475,
-.01923,-.02984,
-.013756,-.032726,
-.007864,-.034617,
-.001734,-.035457,
.00445,-.03522,
.010498,-.033912,
.016227,-.031574,
.01923,-.02984,
.01414,-.02475,
0.0*
4,1,15,-.02475,-.01414,
-.026829,-.009627,
-.028094,-.004822,
-.028504,.000129,
-.028049,.005077,
-.026741,.009871,
-.02475,.01414,
-.02984,.01923,
-.032726,.013756,
-.034617,.007864,
-.035457,.001734,
-.03522,-.00445,
-.033912,-.010498,
-.031574,-.016227,
-.02984,-.01923,
-.02475,-.01414,
0.0*
4,1,15,-.01414,.02475,
-.009627,.026829,
-.004822,.028094,
.000129,.028504,
.005077,.028049,
.009871,.026741,
.01414,.02475,
.01923,.02984,
.013756,.032726,
.007864,.034617,
.001734,.035457,
-.00445,.03522,
-.010498,.033912,
-.016227,.031574,
-.01923,.02984,
-.01414,.02475,
0.0*
%
%ADD24MACRO24*%
%AMMACRO10*
4,1,15,.03682,.01914,
.039584,.012455,
.041146,.005393,
.041457,-.001834,
.040509,-.009005,
.03833,-.015903,
.03682,-.01914,
.04197,-.0243,
.045552,-.016643,
.04775,-.00848,
.048497,-.000059,
.047771,.008363,
.045593,.016531,
.042029,.024197,
.04197,.0243,
.03682,.01914,
0.0*
4,1,15,.01914,-.03682,
.012455,-.039584,
.005393,-.041146,
-.001834,-.041457,
-.009005,-.040509,
-.015903,-.03833,
-.01914,-.03682,
-.0243,-.04197,
-.016643,-.045552,
-.00848,-.04775,
-.000059,-.048497,
.008363,-.047771,
.016531,-.045593,
.024197,-.042029,
.0243,-.04197,
.01914,-.03682,
0.0*
4,1,15,-.03682,-.01914,
-.039584,-.012455,
-.041146,-.005393,
-.041457,.001834,
-.040509,.009005,
-.03833,.015903,
-.03682,.01914,
-.04197,.0243,
-.045552,.016643,
-.04775,.00848,
-.048497,.000059,
-.047771,-.008363,
-.045593,-.016531,
-.042029,-.024197,
-.04197,-.0243,
-.03682,-.01914,
0.0*
4,1,15,-.01914,.03682,
-.012455,.039584,
-.005393,.041146,
.001834,.041457,
.009005,.040509,
.015903,.03833,
.01914,.03682,
.0243,.04197,
.016643,.045552,
.00848,.04775,
.000059,.048497,
-.008363,.047771,
-.016531,.045593,
-.024197,.042029,
-.0243,.04197,
-.01914,.03682,
0.0*
%
%ADD10MACRO10*%
%ADD29C,.111*%
%ADD28C,.17*%
%ADD27O,.156X.219*%
%ADD17C,.144*%
%ADD33C,.154*%
%ADD20C,.155*%
%ADD16C,.146*%
%AMMACRO34*
4,1,36,.0025,0.0,
.002462,.000434,
.002349,.000855,
.002165,.00125,
.001915,.001607,
.001607,.001915,
.00125,.002165,
.000855,.002349,
.000434,.002462,
0.0,.0025,
-.000434,.002462,
-.000855,.002349,
-.00125,.002165,
-.001607,.001915,
-.001915,.001607,
-.002165,.00125,
-.002349,.000855,
-.002462,.000434,
-.0025,0.0,
-.002462,-.000434,
-.002349,-.000855,
-.002165,-.00125,
-.001915,-.001607,
-.001607,-.001915,
-.00125,-.002165,
-.000855,-.002349,
-.000434,-.002462,
0.0,-.0025,
.000434,-.002462,
.000855,-.002349,
.00125,-.002165,
.001607,-.001915,
.001915,-.001607,
.002165,-.00125,
.002349,-.000855,
.002462,-.000434,
.0025,0.0,
45.*
%
%ADD34MACRO34*%
%AMMACRO19*
4,1,36,.0025,0.0,
.002462,.000434,
.002349,.000855,
.002165,.00125,
.001915,.001607,
.001607,.001915,
.00125,.002165,
.000855,.002349,
.000434,.002462,
0.0,.0025,
-.000434,.002462,
-.000855,.002349,
-.00125,.002165,
-.001607,.001915,
-.001915,.001607,
-.002165,.00125,
-.002349,.000855,
-.002462,.000434,
-.0025,0.0,
-.002462,-.000434,
-.002349,-.000855,
-.002165,-.00125,
-.001915,-.001607,
-.001607,-.001915,
-.00125,-.002165,
-.000855,-.002349,
-.000434,-.002462,
0.0,-.0025,
.000434,-.002462,
.000855,-.002349,
.00125,-.002165,
.001607,-.001915,
.001915,-.001607,
.002165,-.00125,
.002349,-.000855,
.002462,-.000434,
.0025,0.0,
90.*
%
%ADD19MACRO19*%
%AMMACRO38*
4,1,36,.003,0.0,
.002954,.000521,
.002819,.001026,
.002598,.0015,
.002298,.001928,
.001928,.002298,
.0015,.002598,
.001026,.002819,
.000521,.002954,
0.0,.003,
-.000521,.002954,
-.001026,.002819,
-.0015,.002598,
-.001928,.002298,
-.002298,.001928,
-.002598,.0015,
-.002819,.001026,
-.002954,.000521,
-.003,0.0,
-.002954,-.000521,
-.002819,-.001026,
-.002598,-.0015,
-.002298,-.001928,
-.001928,-.002298,
-.0015,-.002598,
-.001026,-.002819,
-.000521,-.002954,
0.0,-.003,
.000521,-.002954,
.001026,-.002819,
.0015,-.002598,
.001928,-.002298,
.002298,-.001928,
.002598,-.0015,
.002819,-.001026,
.002954,-.000521,
.003,0.0,
90.*
%
%ADD38MACRO38*%
%AMMACRO18*
4,1,36,.0025,0.0,
.002462,.000434,
.002349,.000855,
.002165,.00125,
.001915,.001607,
.001607,.001915,
.00125,.002165,
.000855,.002349,
.000434,.002462,
0.0,.0025,
-.000434,.002462,
-.000855,.002349,
-.00125,.002165,
-.001607,.001915,
-.001915,.001607,
-.002165,.00125,
-.002349,.000855,
-.002462,.000434,
-.0025,0.0,
-.002462,-.000434,
-.002349,-.000855,
-.002165,-.00125,
-.001915,-.001607,
-.001607,-.001915,
-.00125,-.002165,
-.000855,-.002349,
-.000434,-.002462,
0.0,-.0025,
.000434,-.002462,
.000855,-.002349,
.00125,-.002165,
.001607,-.001915,
.001915,-.001607,
.002165,-.00125,
.002349,-.000855,
.002462,-.000434,
.0025,0.0,
0.0*
%
%ADD18MACRO18*%
%AMMACRO39*
4,1,36,-.003,0.0,
-.002954,.000521,
-.002819,.001026,
-.002598,.0015,
-.002298,.001928,
-.001928,.002298,
-.0015,.002598,
-.001026,.002819,
-.000521,.002954,
0.0,.003,
.000521,.002954,
.001026,.002819,
.0015,.002598,
.001928,.002298,
.002298,.001928,
.002598,.0015,
.002819,.001026,
.002954,.000521,
.003,0.0,
.002954,-.000521,
.002819,-.001026,
.002598,-.0015,
.002298,-.001928,
.001928,-.002298,
.0015,-.002598,
.001026,-.002819,
.000521,-.002954,
0.0,-.003,
-.000521,-.002954,
-.001026,-.002819,
-.0015,-.002598,
-.001928,-.002298,
-.002298,-.001928,
-.002598,-.0015,
-.002819,-.001026,
-.002954,-.000521,
-.003,0.0,
90.*
%
%ADD39MACRO39*%
%AMMACRO13*
4,1,15,.03682,.01914,
.039584,.012455,
.041146,.005393,
.041457,-.001834,
.040509,-.009005,
.03833,-.015903,
.03682,-.01914,
.04197,-.0243,
.045552,-.016643,
.04775,-.00848,
.048497,-.000059,
.047771,.008363,
.045593,.016531,
.042029,.024197,
.04197,.0243,
.03682,.01914,
180.*
4,1,15,.01914,-.03682,
.012455,-.039584,
.005393,-.041146,
-.001834,-.041457,
-.009005,-.040509,
-.015903,-.03833,
-.01914,-.03682,
-.0243,-.04197,
-.016643,-.045552,
-.00848,-.04775,
-.000059,-.048497,
.008363,-.047771,
.016531,-.045593,
.024197,-.042029,
.0243,-.04197,
.01914,-.03682,
180.*
4,1,15,-.03682,-.01914,
-.039584,-.012455,
-.041146,-.005393,
-.041457,.001834,
-.040509,.009005,
-.03833,.015903,
-.03682,.01914,
-.04197,.0243,
-.045552,.016643,
-.04775,.00848,
-.048497,.000059,
-.047771,-.008363,
-.045593,-.016531,
-.042029,-.024197,
-.04197,-.0243,
-.03682,-.01914,
180.*
4,1,15,-.01914,.03682,
-.012455,.039584,
-.005393,.041146,
.001834,.041457,
.009005,.040509,
.015903,.03833,
.01914,.03682,
.0243,.04197,
.016643,.045552,
.00848,.04775,
.000059,.048497,
-.008363,.047771,
-.016531,.045593,
-.024197,.042029,
-.0243,.04197,
-.01914,.03682,
180.*
%
%ADD13MACRO13*%
%AMMACRO12*
4,1,15,-.03682,.01914,
-.039584,.012455,
-.041146,.005393,
-.041457,-.001834,
-.040509,-.009005,
-.03833,-.015903,
-.03682,-.01914,
-.04197,-.0243,
-.045552,-.016643,
-.04775,-.00848,
-.048497,-.000059,
-.047771,.008363,
-.045593,.016531,
-.042029,.024197,
-.04197,.0243,
-.03682,.01914,
180.*
4,1,15,-.01914,-.03682,
-.012455,-.039584,
-.005393,-.041146,
.001834,-.041457,
.009005,-.040509,
.015903,-.03833,
.01914,-.03682,
.0243,-.04197,
.016643,-.045552,
.00848,-.04775,
.000059,-.048497,
-.008363,-.047771,
-.016531,-.045593,
-.024197,-.042029,
-.0243,-.04197,
-.01914,-.03682,
180.*
4,1,15,.03682,-.01914,
.039584,-.012455,
.041146,-.005393,
.041457,.001834,
.040509,.009005,
.03833,.015903,
.03682,.01914,
.04197,.0243,
.045552,.016643,
.04775,.00848,
.048497,.000059,
.047771,-.008363,
.045593,-.016531,
.042029,-.024197,
.04197,-.0243,
.03682,-.01914,
180.*
4,1,15,.01914,.03682,
.012455,.039584,
.005393,.041146,
-.001834,.041457,
-.009005,.040509,
-.015903,.03833,
-.01914,.03682,
-.0243,.04197,
-.016643,.045552,
-.00848,.04775,
-.000059,.048497,
.008363,.047771,
.016531,.045593,
.024197,.042029,
.0243,.04197,
.01914,.03682,
180.*
%
%ADD12MACRO12*%
%ADD41C,.006*%
%ADD44C,.08006*%
%ADD48C,.07306*%
%ADD43C,.06807*%
%ADD47C,.09908*%
%ADD46O,.03004X.06504*%
%ADD45O,.03006X.06506*%
%ADD42C,.16506*%
G75*
%LPD*%
G75*
G36*
G01X-407000Y-793716D02*
X2010999D01*
Y1475775D01*
X-407000D01*
Y-793716D01*
G37*
%LPC*%
G75*
G36*
G01X-15748Y472016D02*
G02X-9874Y466142I0J-5874D01*
G01Y25945D01*
G02X-15748Y20071I-5874J0D01*
G01X-70000D01*
G02X-75874Y25945I0J5874D01*
G01Y466142D01*
G02X-70000Y472016I5874J0D01*
G01X-15748D01*
G37*
G36*
G01X222605Y410745D02*
G02X222972Y411303I367J158D01*
G01X252083D01*
X257586Y405800D01*
G03X258470Y405434I884J885D01*
G01X276354D01*
G03X279046I1346J666D01*
G01X312724D01*
X320890Y397268D01*
Y313025D01*
G03X321256Y312141I1251J0D01*
G01X325185Y308212D01*
G03X326069Y307846I884J885D01*
G01X349250D01*
X350331Y306765D01*
Y301909D01*
G03Y299667I1001J-1121D01*
G01Y293580D01*
X348691Y291940D01*
X319089D01*
X319035Y292057D01*
G03X316305I-1365J-627D01*
G01X316251Y291940D01*
X261568D01*
G03X261500Y291942I-78J-1500D01*
G03X261432Y291940I10J-1502D01*
G01X231303D01*
X230243Y293000D01*
Y302282D01*
X230250Y302308D01*
G03X230302Y302700I-1450J392D01*
G03X230250Y303092I-1502J0D01*
G01X230243Y303118D01*
Y304357D01*
G03X230134Y304810I-999J-1D01*
G03X230302Y305500I-1333J690D01*
G03X228800Y307002I-1502J0D01*
G01X228797D01*
G03X228273Y306907I2J-1502D01*
G01X228152Y306862D01*
X225407Y309607D01*
G03X224700Y309900I-707J-706D01*
G01X214633D01*
G03X212587I-1023J-1101D01*
G01X185414D01*
X183800Y311514D01*
Y325494D01*
X183809Y325523D01*
G03X183874Y325960I-1437J437D01*
G01Y325962D01*
G03X183809Y326399I-1502J0D01*
G01X183800Y326428D01*
Y336013D01*
G03X183507Y336720I-999J0D01*
G01X170698Y349529D01*
X170689Y349596D01*
G03X169396Y350889I-1489J-196D01*
G01X169329Y350898D01*
X167720Y352507D01*
G03X167013Y352800I-707J-706D01*
G01X125818D01*
X125771Y352935D01*
Y352936D01*
G03X122929I-1421J-485D01*
G01Y352935D01*
X122882Y352800D01*
X112600D01*
G03X111893Y352507I0J-999D01*
G01X107013Y347627D01*
X106901Y347657D01*
G03X106564Y347702I-339J-1257D01*
G03X105262Y346400I0J-1302D01*
G03X105307Y346063I1302J2D01*
G01X105337Y345951D01*
X99243Y339857D01*
X99151Y339865D01*
G03X99026Y339870I-122J-1497D01*
G03X97524Y338368I0J-1502D01*
G03X98650Y336914I1502J0D01*
G01X98800Y336875D01*
Y312116D01*
G03Y310284I1189J-916D01*
G01Y308816D01*
G03Y306984I1189J-916D01*
G01Y252300D01*
G03X99093Y251593I999J0D01*
G01X106093Y244593D01*
G03X106800Y244300I707J706D01*
G01X112366D01*
G03X114814I1224J869D01*
G01X121755D01*
G03X122876Y243798I1121J1001D01*
G01X122878D01*
G03X123599Y243983I-1J1502D01*
G01X123730Y244056D01*
X125799Y241987D01*
Y200546D01*
X125664Y200499D01*
G03Y197659I489J-1420D01*
G01X125799Y197612D01*
Y177997D01*
X125681Y177944D01*
G03X124798Y176575I620J-1369D01*
G01Y176574D01*
G03X124886Y176068I1502J1D01*
G01X124929Y175948D01*
X109193Y160212D01*
G03X108900Y159505I706J-707D01*
G01Y150214D01*
X101410Y142724D01*
X90094D01*
G03X88246I-924J-1183D01*
G01X68984D01*
X68945Y142741D01*
G03X67725I-610J-1371D01*
G01X67686Y142724D01*
X25576D01*
G03X24869Y142431I0J-999D01*
G01X20852Y138414D01*
G03X20559Y137707I706J-707D01*
G01Y97549D01*
G03X20852Y96842I999J0D01*
G01X25882Y91812D01*
G03X26589Y91519I707J706D01*
G01X44363D01*
G03X46637I1137J980D01*
G01X47567D01*
X58500Y80586D01*
Y75568D01*
G03X58498Y75500I1500J-78D01*
G03X58500Y75432I1502J10D01*
G01Y68549D01*
G03Y65935I740J-1307D01*
G01Y54258D01*
G03X57923Y53075I924J-1183D01*
G03X59425Y51573I1502J0D01*
G01X59427D01*
G03X59818Y51625I-1J1502D01*
G01X59930Y51656D01*
X65393Y46193D01*
G03X66100Y45900I707J706D01*
G01X99400D01*
G03X100107Y46193I0J999D01*
G01X109607Y55693D01*
G03X109900Y56400I-706J707D01*
G01Y61086D01*
X140324Y91510D01*
X150564D01*
X181803Y91519D01*
X195709Y77613D01*
G03X196416Y77320I707J706D01*
G01X223752D01*
G03X224459Y77613I0J999D01*
G01X227870Y81024D01*
X227939Y81033D01*
G03X229251Y82344I-179J1491D01*
G01Y82345D01*
X229260Y82414D01*
X237878Y91032D01*
G02X238476Y90996I283J-283D01*
G03X239660Y90418I1184J924D01*
G03X241065Y91390I0J1501D01*
G01X241114Y91519D01*
X261606D01*
X261643Y91367D01*
G03X264561I1459J358D01*
G01X264598Y91519D01*
X272616D01*
G03X274184I784J1280D01*
G01X275117D01*
G03X277683I1283J781D01*
G01X349234D01*
X350331Y90422D01*
Y81909D01*
G03Y79667I1001J-1121D01*
G01Y61909D01*
G03Y59667I1001J-1121D01*
G01Y41909D01*
G03Y39667I1001J-1121D01*
G01Y21909D01*
G03Y19667I1001J-1121D01*
G01Y7874D01*
G02X346457Y4000I-3874J0D01*
G01X343339D01*
G03X341097I-1121J-1001D01*
G01X323339D01*
G03X321097I-1121J-1001D01*
G01X303339D01*
G03X301097I-1121J-1001D01*
G01X283339D01*
G03X281097I-1121J-1001D01*
G01X263339D01*
G03X261097I-1121J-1001D01*
G01X243339D01*
G03X241097I-1121J-1001D01*
G01X223339D01*
G03X221097I-1121J-1001D01*
G01X203339D01*
G03X201097I-1121J-1001D01*
G01X183339D01*
G03X181097I-1121J-1001D01*
G01X163339D01*
G03X161097I-1121J-1001D01*
G01X143339D01*
G03X141097I-1121J-1001D01*
G01X123339D01*
G03X121097I-1121J-1001D01*
G01X103339D01*
G03X101097I-1121J-1001D01*
G01X83339D01*
G03X81097I-1121J-1001D01*
G01X63339D01*
G03X61097I-1121J-1001D01*
G01X43339D01*
G03X41097I-1121J-1001D01*
G01X23339D01*
G03X21097I-1121J-1001D01*
G01X7874D01*
G02X4029Y7400I0J3874D01*
G03X4502Y8494I-1029J1094D01*
G03X4000Y9615I-1503J0D01*
G01Y27373D01*
G03Y29615I-1001J1121D01*
G01Y47373D01*
G03Y49615I-1001J1121D01*
G01Y67373D01*
G03Y69615I-1001J1121D01*
G01Y87373D01*
G03Y89615I-1001J1121D01*
G01Y107373D01*
G03Y109615I-1001J1121D01*
G01Y127373D01*
G03Y129615I-1001J1121D01*
G01Y147373D01*
G03Y149615I-1001J1121D01*
G01Y167373D01*
G03Y169615I-1001J1121D01*
G01Y187373D01*
G03Y189615I-1001J1121D01*
G01Y205127D01*
X20220D01*
G03X22280I1030J1092D01*
G01X62624D01*
G03X63508Y205493I0J1251D01*
G01X65891Y207876D01*
G03X66257Y208760I-885J884D01*
G01Y230521D01*
G03X65891Y231405I-1251J0D01*
G01X61349Y235947D01*
X61341Y236015D01*
G03X60035Y237321I-1491J-185D01*
G01X59967Y237329D01*
X48783Y248513D01*
Y283467D01*
G03X48417Y284351I-1251J0D01*
G01X46350Y286418D01*
Y306182D01*
X47357Y307189D01*
X47440D01*
G03X48942Y308691I0J1502D01*
G01Y308692D01*
G03X48783Y309364I-1502J-1D01*
G01Y311407D01*
G03X48942Y312079I-1343J673D01*
G01Y312081D01*
G03X48783Y312753I-1502J-1D01*
G01Y320152D01*
X48917Y320199D01*
G03Y323033I-496J1417D01*
G01X48783Y323080D01*
Y404096D01*
X55990Y411303D01*
X94373D01*
G03X96187I907J1196D01*
G01X97074D01*
G03X99126I1026J1097D01*
G01X106846D01*
X106886Y411155D01*
G03X109786I1450J392D01*
G01X109826Y411303D01*
X111876D01*
G03X113716I920J1186D01*
G01X115134D01*
X115171Y411150D01*
G03X118093I1461J350D01*
G01X118130Y411303D01*
X118669D01*
G03X120913I1122J997D01*
G01X139477D01*
G03X141723I1123J996D01*
G01X151749D01*
G03X154409I1330J696D01*
G01X215978D01*
G02X216345Y410745I0J-400D01*
G03X216222Y410150I1380J-595D01*
G03X217723Y408648I1502J0D01*
G01X221225D01*
G03X222728Y410150I0J1503D01*
G03X222605Y410745I-1503J0D01*
G37*
G36*
G01X24194Y466518D02*
G03X24144Y466901I-1502J-1D01*
G02X24531Y467404I387J103D01*
G01X38382D01*
Y451968D01*
G03X39366Y448685I5969J0D01*
G03X39346Y448441I1482J-244D01*
G01Y448440D01*
G03X40848Y446938I1502J0D01*
G03X41104Y446960I0J1502D01*
G03X44349Y446000I3246J5009D01*
G01X50257D01*
G03X53760Y447137I-1J5969D01*
G03X54100Y447098I340J1463D01*
G03X55602Y448600I0J1502D01*
G03X55506Y449130I-1502J2D01*
G03X56216Y451653I-5250J2839D01*
G02X56423Y451843I200J-10D01*
G03X56482Y451842I55J1501D01*
G03X57984Y453344I0J1502D01*
G01Y456844D01*
G03X56594Y458342I-1502J0D01*
G02X56224Y458741I30J399D01*
G01Y462100D01*
X120508D01*
Y451870D01*
G03X139158Y450055I9413J0D01*
G03X140252Y451500I-407J1445D01*
G03X139673Y452685I-1502J0D01*
G02Y453315I246J315D01*
G03X140252Y454500I-923J1185D01*
G03X139680Y455679I-1501J0D01*
G02X139628Y456258I248J314D01*
G03X140002Y457250I-1129J992D01*
G03X139335Y458499I-1503J0D01*
G01Y462100D01*
X170547D01*
Y451836D01*
G03X169898Y450600I852J-1236D01*
G03X170585Y449338I1503J0D01*
G03X178189Y442456I7604J760D01*
G03X185831Y450098I0J7642D01*
G01Y450245D01*
X185910Y450305D01*
G03X186502Y451500I-910J1195D01*
G03X186132Y452487I-1501J0D01*
G02Y453013I302J263D01*
G03Y454987I-1131J987D01*
G02Y455513I302J263D01*
G03X186502Y456500I-1131J987D01*
G03X185831Y457751I-1502J0D01*
G01Y462100D01*
X250075D01*
Y450886D01*
G03X258504Y442457I8429J0D01*
G01X258505D01*
G03X259916Y442576I0J8429D01*
G03X261100Y441998I1184J924D01*
G03X262602Y443500I0J1502D01*
G01Y443520D01*
G03X266933Y450886I-4098J7366D01*
G01Y462100D01*
X298126D01*
Y451968D01*
G03X304093Y446000I5969J0D01*
G01X310000D01*
G03X315969Y451969I0J5969D01*
G01Y455406D01*
G03Y457648I-1001J1121D01*
G01Y467404D01*
X329803D01*
G02X330190Y466905I-1J-400D01*
G03X330144Y466536I1457J-369D01*
G03X330646Y465415I1503J0D01*
G01Y451968D01*
G03X332616Y447538I5968J1D01*
G03X334112Y446166I1496J130D01*
G03X334738Y446303I-1J1502D01*
G03X336613Y446000I1878J5665D01*
G01X346457D01*
G02X350331Y442126I0J-3874D01*
G01Y438652D01*
G03Y436410I1001J-1121D01*
G01Y418652D01*
G03Y416410I1001J-1121D01*
G01Y398652D01*
G03Y396410I1001J-1121D01*
G01Y378652D01*
G03Y376410I1001J-1121D01*
G01Y358652D01*
G03Y356410I1001J-1121D01*
G01Y339436D01*
G02X349796Y339060I-400J1D01*
G03X349290Y339148I-507J-1414D01*
G03X348169Y338646I0J-1503D01*
G01X345471D01*
G03X339504Y332678I2J-5968D01*
G01Y322834D01*
G03X341102Y318770I5968J1D01*
G03X342604Y317271I1502J3D01*
G01X342606D01*
G03X343103Y317356I-1J1502D01*
G03X345471Y316866I2368J5479D01*
G01X350331D01*
Y311743D01*
X348934Y310346D01*
X326587D01*
X323390Y313543D01*
Y397786D01*
G03X323024Y398670I-1251J0D01*
G01X314126Y407568D01*
G03X313242Y407934I-884J-885D01*
G01X258988D01*
X253834Y413088D01*
X253822Y413147D01*
G03X252350Y414352I-1472J-297D01*
G03X251189Y413803I0J-1502D01*
G01X207287D01*
G03X205013I-1137J-983D01*
G01X113527D01*
X113484Y413825D01*
G03X112108I-688J-1334D01*
G01X112065Y413803D01*
X98637D01*
X98605Y413815D01*
G03X98100Y413902I-504J-1415D01*
G03X97595Y413815I-1J-1502D01*
G01X97563Y413803D01*
X96029D01*
X95985Y413826D01*
G03X95280Y414002I-705J-1326D01*
G03X94575Y413826I0J-1502D01*
G01X94531Y413803D01*
X79056D01*
X79009Y413936D01*
G03X77592Y414939I-1417J-499D01*
G03X76611Y414574I0J-1501D01*
G02X76020Y414651I-261J303D01*
G03X74782Y415302I-1238J-852D01*
G03X73291Y413979I0J-1502D01*
G01X73270Y413803D01*
X70606D01*
X70560Y413938D01*
G03X69139Y414954I-1421J-486D01*
G03X68040Y414476I0J-1502D01*
G02X67447Y414484I-293J272D01*
G03X66319Y414994I-1128J-992D01*
G03X64886Y413943I0J-1502D01*
G01X64842Y413803D01*
X55472D01*
G03X54588Y413437I0J-1251D01*
G01X46649Y405498D01*
G03X46283Y404614I885J-884D01*
G01Y393006D01*
G03Y390454I792J-1276D01*
G01Y313038D01*
G03Y311122I1158J-958D01*
G01Y309651D01*
X44216Y307584D01*
G03X43850Y306700I885J-884D01*
G01Y285900D01*
G03X44216Y285016I1251J0D01*
G01X46283Y282949D01*
Y247995D01*
G03X46649Y247111I1251J0D01*
G01X58435Y235325D01*
X58450Y235286D01*
G03X59306Y234430I1400J544D01*
G01X59345Y234415D01*
X63757Y230003D01*
Y209278D01*
X62106Y207627D01*
X21777D01*
X21745Y207638D01*
G03X21250Y207722I-495J-1418D01*
G03X20755Y207638I0J-1502D01*
G01X20723Y207627D01*
X4844D01*
G02X4456Y208125I0J400D01*
G03X4502Y208494I-1457J369D01*
G03X4000Y209615I-1503J0D01*
G01Y227373D01*
G03Y229615I-1001J1121D01*
G01Y247373D01*
G03Y249615I-1001J1121D01*
G01Y267373D01*
G03Y269615I-1001J1121D01*
G01Y287373D01*
G03Y289615I-1001J1121D01*
G01Y307373D01*
G03Y309615I-1001J1121D01*
G01Y316866D01*
X8858D01*
G03X14827Y322835I0J5969D01*
G01Y324189D01*
G03Y326431I-1001J1121D01*
G01Y332677D01*
G03X8858Y338646I-5969J0D01*
G01X4000D01*
Y341005D01*
G03Y343247I-1001J1121D01*
G01Y361005D01*
G03Y363247I-1001J1121D01*
G01Y381005D01*
G03Y383247I-1001J1121D01*
G01Y401005D01*
G03Y403247I-1001J1121D01*
G01Y421005D01*
G03Y423247I-1001J1121D01*
G01Y441005D01*
G03X4502Y442126I-1001J1121D01*
G03X4129Y443117I-1503J0D01*
G02X7874Y446000I3745J-991D01*
G01X17718D01*
G03X19600Y446305I-2J5968D01*
G03X20224Y446169I625J1366D01*
G01X20225D01*
G03X21722Y447543I0J1503D01*
G03X23685Y451968I-4006J4425D01*
G01Y465391D01*
G03X24194Y466518I-993J1127D01*
G37*
G36*
G01X127799Y176486D02*
G03X127802Y176575I-1499J95D01*
G03X127799Y176664I-1502J-6D01*
G01Y242401D01*
G03X127506Y243108I-999J0D01*
G01X124607Y246007D01*
G03X124001Y246295I-707J-706D01*
G03X122876Y246802I-1125J-995D01*
G03X121755Y246300I0J-1503D01*
G01X114579D01*
G03X112601I-989J-1129D01*
G01X107214D01*
X100800Y252714D01*
Y292092D01*
X100965Y292122D01*
G03Y295078I-264J1478D01*
G01X100800Y295108D01*
Y306635D01*
G03Y309165I-810J1265D01*
G01Y309935D01*
G03Y312465I-810J1265D01*
G01Y327068D01*
X100941Y327111D01*
G03Y329983I-441J1436D01*
G01X100800Y330026D01*
Y338586D01*
X113014Y350800D01*
X113246D01*
X113294Y350671D01*
G03X116106I1406J529D01*
G01X116154Y350800D01*
X166599D01*
X167721Y349678D01*
X167709Y349582D01*
G03X167698Y349401I1491J-181D01*
G01Y349400D01*
G03X169200Y347898I1502J0D01*
G01X169201D01*
G03X169382Y347909I0J1502D01*
G01X169478Y347921D01*
X181800Y335599D01*
Y327355D01*
X181691Y327300D01*
G03Y324622I681J-1339D01*
G01X181800Y324567D01*
Y311100D01*
G03X182093Y310393I999J0D01*
G01X184293Y308193D01*
G03X185000Y307900I707J706D01*
G01X190998D01*
X191047Y307772D01*
G03X193849I1401J542D01*
G01X193898Y307900D01*
X212408D01*
G03X214812I1202J899D01*
G01X224286D01*
X227639Y304547D01*
G03X227840Y304345I1160J954D01*
G01X227847Y304339D01*
X228098Y304088D01*
X227945Y303935D01*
X227931Y303925D01*
G03X227298Y302700I869J-1225D01*
G03X228132Y301355I1502J0D01*
G01X228243Y301300D01*
Y292966D01*
X227217Y291940D01*
X224569D01*
G03X222775I-897J-1206D01*
G01X193891D01*
X193867Y292112D01*
G03X190893I-1487J-212D01*
G01X190869Y291940D01*
X163570D01*
X163524Y292077D01*
G03X160676I-1424J-477D01*
G01X160630Y291940D01*
X156875D01*
X154900Y293915D01*
Y336900D01*
G03X154607Y337607I-999J0D01*
G01X151307Y340907D01*
G03X150600Y341200I-707J-706D01*
G01X137497D01*
X137460Y341353D01*
G03X134540I-1460J-353D01*
G01X134503Y341200D01*
X124500D01*
G03X123793Y340907I0J-999D01*
G01X113993Y331107D01*
G03X113700Y330400I706J-707D01*
G01Y274452D01*
G03Y272948I1299J-752D01*
G01Y264400D01*
G03X113993Y263693I999J0D01*
G01X117093Y260593D01*
G03X117800Y260300I707J706D01*
G01X137286D01*
X140216Y257370D01*
G03X139778Y256310I1064J-1060D01*
G03X141280Y254808I1502J0D01*
G03X142340Y255246I0J1502D01*
G01X146851Y250735D01*
Y221413D01*
X146833Y221374D01*
G03Y220556I913J-409D01*
G01X146851Y220517D01*
Y201953D01*
G03Y199625I949J-1164D01*
G01Y179013D01*
X146678Y178989D01*
G03Y176013I204J-1488D01*
G01X146851Y175989D01*
Y132510D01*
G03X147144Y131803I999J0D01*
G01X148833Y130114D01*
G03X149540Y129821I707J706D01*
G01X154517D01*
G02X154914Y129375I0J-400D01*
G03X154904Y129203I1492J-173D01*
G03X155999Y127757I1502J0D01*
G01X156145Y127716D01*
Y126407D01*
X155985Y126375D01*
G03Y123431I302J-1472D01*
G01X156145Y123399D01*
Y120586D01*
G03X156438Y119879I999J0D01*
G01X161440Y114877D01*
G03X162147Y114584I707J706D01*
G01X183876D01*
G03X185582I853J1235D01*
G01X191990D01*
G03X194202I1106J1015D01*
G01X237405D01*
X237444Y114433D01*
G03X240356I1456J366D01*
G01X240395Y114584D01*
X322958D01*
G03X324023Y114141I1065J1059D01*
G03X325525Y115643I0J1502D01*
G03X325461Y116075I-1502J-2D01*
G01X325427Y116190D01*
X325804Y116567D01*
G03X326097Y117274I-706J707D01*
G01Y129638D01*
X328921Y132462D01*
X348611D01*
X350210Y130863D01*
G03X350331Y130760I707J707D01*
G01Y121909D01*
G03Y119667I1001J-1121D01*
G01Y101909D01*
G03Y99667I1001J-1121D01*
G01Y94462D01*
X349388Y93519D01*
X341988D01*
G03X318642I-11673J-4187D01*
G01X277278D01*
G03X276400Y93802I-878J-1219D01*
G03X275522Y93519I0J-1502D01*
G01X274719D01*
G03X272081I-1319J-719D01*
G01X237951D01*
G03X237244Y93226I0J-999D01*
G01X228024Y84006D01*
X227928Y84017D01*
G03X227760Y84026I-164J-1493D01*
G03X226258Y82524I0J-1502D01*
G03X226267Y82356I1502J-4D01*
G01X226278Y82260D01*
X223338Y79320D01*
X196830D01*
X192524Y83626D01*
G03X192814Y84512I-1212J887D01*
G03X191312Y86014I-1502J0D01*
G03X190553Y85808I0J-1501D01*
G01X190420Y85730D01*
X182924Y93226D01*
G03X182217Y93519I-707J-706D01*
G01X150564Y93510D01*
X139910D01*
G03X139203Y93217I0J-999D01*
G01X129981Y83995D01*
X129859Y84044D01*
G03X129300Y84152I-559J-1393D01*
G03X127798Y82650I0J-1502D01*
G03X127906Y82091I1501J0D01*
G01X127955Y81969D01*
X108193Y62207D01*
G03X107900Y61500I706J-707D01*
G01Y56814D01*
X98986Y47900D01*
X66514D01*
X60844Y53570D01*
X60828Y53610D01*
G03X60500Y54124I-1404J-534D01*
G01Y66424D01*
G03X60742Y67242I-1260J818D01*
G03X60500Y68060I-1502J0D01*
G01Y74078D01*
X60618Y74131D01*
G03Y76869I-618J1369D01*
G01X60500Y76922D01*
Y81000D01*
G03X60207Y81707I-999J0D01*
G01X48688Y93226D01*
G03X47981Y93519I-707J-706D01*
G01X46603D01*
G03X44397I-1103J-1018D01*
G01X35689D01*
G03X24016Y101733I-11673J-4187D01*
G01X24008D01*
G03X22992Y101691I4J-12402D01*
G02X22559Y102089I-33J398D01*
G01Y137293D01*
X25990Y140724D01*
X66979D01*
G03X69691I1356J644D01*
G01X87909D01*
G03X90431I1261J816D01*
G01X101824D01*
G03X102531Y141017I0J999D01*
G01X110607Y149093D01*
G03X110900Y149800I-706J707D01*
G01Y159091D01*
X127136Y175327D01*
X127151Y175337D01*
G03X127555Y175749I-851J1238D01*
G03X127799Y176403I-756J654D01*
G01Y176486D01*
G37*
G36*
G01X155754Y290233D02*
G03X156461Y289940I707J706D01*
G01X209821D01*
X211015Y288746D01*
Y279055D01*
G03X211308Y278348I999J0D01*
G01X214760Y274896D01*
G03X215467Y274603I707J706D01*
G01X222203D01*
X224400Y276800D01*
X230303D01*
X232500Y274603D01*
X268807D01*
X273020Y270390D01*
Y175522D01*
G03Y173012I623J-1255D01*
G01Y150310D01*
X270795Y148085D01*
X168036D01*
G03X167329Y147792I0J-999D01*
G01X156438Y136901D01*
G03X156145Y136194I706J-707D01*
G01Y132733D01*
X155233Y131821D01*
X149954D01*
X148851Y132924D01*
Y146234D01*
X148978Y146284D01*
G03Y149080I-549J1398D01*
G01X148851Y149130D01*
Y154326D01*
X148974Y154377D01*
G03Y157153I-574J1388D01*
G01X148851Y157204D01*
Y199716D01*
G03Y201862I-1051J1073D01*
G01Y220613D01*
X148852Y220616D01*
G03X148876Y220835I-976J218D01*
G03X148852Y221054I-1000J1D01*
G01X148851Y221057D01*
Y251149D01*
G03X148558Y251856I-999J0D01*
G01X138407Y262007D01*
G03X137700Y262300I-707J-706D01*
G01X118214D01*
X115700Y264814D01*
Y272371D01*
G03Y275029I-700J1329D01*
G01Y329986D01*
X124914Y339200D01*
X150186D01*
X152900Y336486D01*
Y293501D01*
G03X153193Y292794I999J0D01*
G01X155754Y290233D01*
G37*
G36*
G01X317860Y289940D02*
X348671D01*
X350206Y288405D01*
G03X350331Y288299I707J707D01*
G01Y281909D01*
G03Y279667I1001J-1121D01*
G01Y261909D01*
G03Y259667I1001J-1121D01*
G01Y241909D01*
G03Y239667I1001J-1121D01*
G01Y221909D01*
G03Y219667I1001J-1121D01*
G01Y201909D01*
G03Y199667I1001J-1121D01*
G01Y181909D01*
G03Y179667I1001J-1121D01*
G01Y161909D01*
G03Y159667I1001J-1121D01*
G01Y141909D01*
G03Y139667I1001J-1121D01*
G01Y136034D01*
X348759Y134462D01*
X328507D01*
G03X327800Y134169I0J-999D01*
G01X324263Y130632D01*
G03X323970Y129925I706J-707D01*
G03X324076Y129477I1000J0D01*
G01X324097Y129435D01*
Y117688D01*
X323434Y117025D01*
X323401Y117010D01*
G03X322852Y116584I621J-1367D01*
G01X316599D01*
X316563Y116739D01*
G03X313637I-1463J-339D01*
G01X313601Y116584D01*
X305509D01*
X305481Y116751D01*
G03X302519I-1481J-251D01*
G01X302491Y116584D01*
X194231D01*
G03X191961I-1135J-984D01*
G01X186022D01*
G03X183436I-1293J-764D01*
G01X162561D01*
X158145Y121000D01*
Y135780D01*
X168450Y146085D01*
X170605D01*
X170643Y145934D01*
G03X173557I1457J366D01*
G01X173595Y146085D01*
X257024D01*
X257068Y145946D01*
G03X259932I1432J454D01*
G01X259976Y146085D01*
X271209D01*
G03X271916Y146378I0J999D01*
G01X274727Y149189D01*
G03X275020Y149896I-706J707D01*
G01Y173998D01*
X275023Y174015D01*
G03X275046Y174267I-1379J253D01*
G03X275023Y174519I-1402J-1D01*
G01X275020Y174536D01*
Y270804D01*
G03X274727Y271511I-999J0D01*
G01X269928Y276310D01*
G03X269221Y276603I-707J-706D01*
G01X233297D01*
X231100Y278800D01*
X223597D01*
X221400Y276603D01*
X215881D01*
X213015Y279469D01*
Y288950D01*
X214005Y289940D01*
X222398D01*
G03X224946I1274J794D01*
G01X260078D01*
X260131Y289822D01*
G03X262869I1369J618D01*
G01X262922Y289940D01*
X317480D01*
X317492Y289939D01*
G03X317670Y289928I181J1491D01*
G03X317848Y289939I-3J1502D01*
G01X317860Y289940D01*
G37*
G36*
G01X364205Y466142D02*
G02X370079Y472016I5874J0D01*
G01X476378D01*
G02X482252Y466142I0J-5874D01*
G01Y-509842D01*
G02X476378Y-515716I-5874J0D01*
G01X370079D01*
G02X364205Y-509842I0J5874D01*
G01Y466142D01*
G37*
%LPD*%
G75*
G36*
G01X100538Y200527D02*
G03X100524Y201264I-162J366D01*
G02X92322Y213343I4793J12079D01*
G02X118310I12994J0D01*
G02X110107Y201264I-12995J0D01*
G03X110093Y200526I147J-372D01*
G02X117130Y189721I-4777J-10805D01*
G01Y183421D01*
G02X93500I-11815J0D01*
G01Y189721D01*
G02X100538Y200527I11815J0D01*
G37*
G36*
G01X182350Y387136D02*
G02Y384132I0J-1502D01*
G01X178850D01*
G02Y387136I0J1502D01*
G01X182350D01*
G37*
G36*
G01X162550Y388836D02*
G02Y385832I0J-1502D01*
G01X159050D01*
G02Y388836I0J1502D01*
G01X162550D01*
G37*
G36*
G01X176859Y55780D02*
G02Y61386I0J2803D01*
G01X184733D01*
G02Y55780I0J-2803D01*
G01X176859D01*
G37*
G36*
G01X165048Y49874D02*
G02Y55480I0J2803D01*
G01X172922D01*
G02Y49874I0J-2803D01*
G01X165048D01*
G37*
G36*
G01X153237Y55780D02*
G02Y61386I0J2803D01*
G01X161111D01*
G02Y55780I0J-2803D01*
G01X153237D01*
G37*
G36*
G01X72150Y422696D02*
G02Y425702I0J1503D01*
G01X75650D01*
G02Y422696I0J-1503D01*
G01X72150D01*
G37*
G36*
G01X92801Y451290D02*
G02Y454296I0J1503D01*
G01X96301D01*
G02Y451290I0J-1503D01*
G01X92801D01*
G37*
G36*
G01X60622Y429770D02*
G02Y432776I0J1503D01*
G01X64122D01*
G02Y429770I0J-1503D01*
G01X60622D01*
G37*
G36*
G01X216725Y443722D02*
G02Y440718I0J-1502D01*
G01X213225D01*
G02Y443722I0J1502D01*
G01X216725D01*
G37*
G36*
G01X81990Y446582D02*
G02Y449588I0J1503D01*
G01X85490D01*
G02Y446582I0J-1503D01*
G01X81990D01*
G37*
G36*
G01X52750Y422698D02*
G02Y425702I0J1502D01*
G01X56250D01*
G02Y422698I0J-1502D01*
G01X52750D01*
G37*
G36*
G01X95870Y443980D02*
G02Y446986I0J1503D01*
G01X99370D01*
G02Y443980I0J-1503D01*
G01X95870D01*
G37*
G36*
G01X246488Y104290D02*
G02Y107294I0J1502D01*
G01X249988D01*
G02Y104290I0J-1502D01*
G01X246488D01*
G37*
G36*
G01X255213Y104596D02*
G02Y107602I0J1503D01*
G01X258713D01*
G02Y104596I0J-1503D01*
G01X255213D01*
G37*
G36*
G01X169347Y94778D02*
G02Y97784I0J1503D01*
G01X172847D01*
G02Y94778I0J-1503D01*
G01X169347D01*
G37*
G36*
G01X159923D02*
G02Y97784I0J1503D01*
G01X163423D01*
G02Y94778I0J-1503D01*
G01X159923D01*
G37*
G36*
G01X242870Y239000D02*
G02X243872Y238580I0J-1405D01*
G02Y236612I-853J-984D01*
G02X242870Y236192I-1002J985D01*
G02X242378Y236281I0J1404D01*
G01X242344Y236294D01*
X240395D01*
G02X239870Y236192I-525J1302D01*
G02Y239000I0J1404D01*
G02X240395Y238898I0J-1404D01*
G01X242344D01*
X242378Y238911D01*
G02X242870Y239000I492J-1315D01*
G37*
G36*
G01X239998Y225853D02*
Y229002D01*
G02X242602I1302J0D01*
G01Y226194D01*
G02X242638Y225890I-1264J-304D01*
G02X242261Y224974I-1301J0D01*
G02X241300Y224551I-961J880D01*
G02X239998Y225853I0J1302D01*
G37*
G36*
G01X250749Y236604D02*
X253898D01*
G02Y233998I0J-1303D01*
G01X250749D01*
G02Y236604I0J1303D01*
G37*
G36*
G01X253898Y233454D02*
X257047D01*
G02Y230848I0J-1303D01*
G01X253898D01*
G02Y233454I0J1303D01*
G37*
G36*
G01X244450D02*
X247599D01*
G02Y230848I0J-1303D01*
G01X244450D01*
G02Y233454I0J1303D01*
G37*
G36*
G01X250749Y230304D02*
X253898D01*
G02Y227700I0J-1302D01*
G01X250749D01*
G02Y230304I0J1302D01*
G37*
G36*
G01X267722Y175288D02*
X264222D01*
G02Y178294I0J1503D01*
G01X267722D01*
G02Y175288I0J-1503D01*
G37*
G36*
G01X266080Y205760D02*
X262580D01*
G02Y208764I0J1502D01*
G01X266080D01*
G02Y205760I0J-1502D01*
G37*
G36*
G01X267080Y213090D02*
X263580D01*
G02Y216096I0J1503D01*
G01X267080D01*
G02Y213090I0J-1503D01*
G37*
G36*
G01X375904Y-439648D02*
G02Y-436642I0J1503D01*
G01X379304D01*
G02Y-439648I0J-1503D01*
G01X375904D01*
G37*
G36*
G01X375964Y-217462D02*
G02Y-214456I0J1503D01*
G01X379364D01*
G02Y-217462I0J-1503D01*
G01X375964D01*
G37*
G36*
G01X375876Y-161376D02*
G02Y-158370I0J1503D01*
G01X379276D01*
G02Y-161376I0J-1503D01*
G01X375876D01*
G37*
G36*
G01X397080Y-122524D02*
G02Y-119518I0J1503D01*
G01X400480D01*
G02Y-122524I0J-1503D01*
G01X397080D01*
G37*
G36*
G01X375964Y10810D02*
G02Y13816I0J1503D01*
G01X379364D01*
G02Y10810I0J-1503D01*
G01X375964D01*
G37*
G36*
G01X375904Y66896D02*
G02Y69902I0J1503D01*
G01X379304D01*
G02Y66896I0J-1503D01*
G01X375904D01*
G37*
G36*
G01X375964Y380082D02*
G02Y383088I0J1503D01*
G01X379364D01*
G02Y380082I0J-1503D01*
G01X375964D01*
G37*
G36*
G01X396992Y-465710D02*
G02Y-462704I0J1503D01*
G01X400392D01*
G02Y-465710I0J-1503D01*
G01X396992D01*
G37*
G54D44*
X65945Y297776D03*
G54D48*
X403692Y-481375D03*
X393692D03*
Y-456375D03*
X403692D03*
X382604Y-455313D03*
X372604D03*
Y-430313D03*
X382604D03*
X382664Y373753D03*
X372664D03*
Y398753D03*
X382664D03*
X393750Y272050D03*
X403750D03*
Y247050D03*
X393750D03*
Y200538D03*
X403750D03*
Y225538D03*
X393750D03*
X393780Y-128853D03*
X403780D03*
Y-103853D03*
X393780D03*
X403750Y-57222D03*
X393750D03*
Y-82222D03*
X403750D03*
X372604Y76231D03*
X382604D03*
Y51231D03*
X372604D03*
X413750Y-57222D03*
Y-82222D03*
X382664Y4481D03*
X372664D03*
Y29481D03*
X382664D03*
X403750Y398810D03*
X413750D03*
Y423810D03*
X403750D03*
X413750Y200538D03*
Y225538D03*
Y272050D03*
Y247050D03*
X372664Y-223791D03*
X382664D03*
Y-198791D03*
X372664D03*
X393750Y398810D03*
Y423810D03*
X372576Y-152041D03*
X382576D03*
Y-177041D03*
X372576D03*
G54D43*
X291733Y20040D03*
X264173D03*
X336615Y18465D03*
X309055D03*
X17716D03*
X45276D03*
G54D47*
X144685Y297776D03*
G54D46*
X102190Y64975D03*
G54D45*
X63569Y455094D03*
G54D42*
X-58189Y454331D03*
X27300Y68200D03*
X340639Y432809D03*
X464567Y-498031D03*
Y454331D03*
G54D14*
X3000Y8494D03*
Y28494D03*
Y48494D03*
Y68494D03*
Y88494D03*
Y108494D03*
Y128494D03*
Y148494D03*
Y168494D03*
Y188494D03*
Y208494D03*
Y228494D03*
Y248494D03*
Y268494D03*
Y288494D03*
Y308494D03*
Y342126D03*
Y362126D03*
Y382126D03*
Y402126D03*
Y422126D03*
Y442126D03*
X9407Y10554D03*
X12900Y105500D03*
X12500Y102000D03*
X16626Y195848D03*
X19129D03*
Y193048D03*
X16626D03*
X19100Y187420D03*
X19129Y204248D03*
X17000Y208017D03*
Y211541D03*
X16626Y198648D03*
Y201448D03*
X19129Y198648D03*
Y201448D03*
X16626Y204248D03*
X17000Y215713D03*
Y219288D03*
X18000Y240900D03*
Y237900D03*
Y249900D03*
Y246900D03*
Y243900D03*
X17065Y255712D03*
X15688Y259063D03*
X13736Y299891D03*
X6200Y312900D03*
X8300Y314700D03*
X13736Y303280D03*
X13827Y325310D03*
X13869Y352239D03*
X14000Y401700D03*
Y406700D03*
Y404200D03*
X17700Y427600D03*
X14600Y422500D03*
X14700Y425000D03*
X22218Y3000D03*
X27323Y25842D03*
X23723Y123791D03*
Y120791D03*
X32223Y123791D03*
Y120791D03*
X25200Y116300D03*
X31890Y110400D03*
X31920Y186610D03*
X21250Y206220D03*
X21135Y236587D03*
X21205Y232767D03*
X21135Y240667D03*
Y243737D03*
X24690Y246467D03*
Y251967D03*
X21135Y246837D03*
X21035Y249937D03*
X24690Y249267D03*
X24705Y258767D03*
X22237Y304626D03*
X30638Y304602D03*
X22237Y301237D03*
X30638Y301213D03*
X22237Y311481D03*
Y308592D03*
X30638Y311957D03*
Y309068D03*
X30700Y315500D03*
X33000Y318700D03*
X25811Y319400D03*
X32000Y326300D03*
X23535Y329990D03*
X23810Y322534D03*
X31300Y329900D03*
X31000Y342500D03*
X34300Y375000D03*
X26300Y374400D03*
X36200Y368400D03*
X31600Y379600D03*
X33100Y392100D03*
X32700Y395381D03*
X20600Y428900D03*
X25202Y425329D03*
X29400Y430900D03*
X23677Y422419D03*
X31500Y428500D03*
X32100Y432800D03*
X20225Y447671D03*
X22692Y466518D03*
X42218Y3000D03*
X35044Y35751D03*
X43926Y62248D03*
X45500Y92500D03*
X45276Y98488D03*
X40340Y100710D03*
X45001Y95144D03*
X40723Y123791D03*
Y120791D03*
X49223Y123791D03*
Y121291D03*
X38300Y109200D03*
X48500Y112559D03*
X40940D03*
X47294Y184491D03*
X36599Y189016D03*
X37360Y194050D03*
X37823Y198346D03*
X48035Y191535D03*
X39408Y195990D03*
X47714Y212227D03*
X48940Y204871D03*
X47948Y201000D03*
X39900Y211000D03*
X48059Y214825D03*
X48023Y217860D03*
X39800Y213800D03*
X35700Y218000D03*
X39567Y243133D03*
X40500Y236900D03*
X35600Y241200D03*
Y238200D03*
X41574Y255937D03*
X37485Y258807D03*
X41100Y248900D03*
X46220Y277170D03*
X39039Y301299D03*
X47440Y308691D03*
X39039Y309044D03*
Y311933D03*
X47440Y312080D03*
X39039Y304278D03*
X50950Y318050D03*
X43500Y317100D03*
X48420Y321616D03*
X44200Y332000D03*
X44525Y324000D03*
X39100Y321600D03*
X44481Y328760D03*
X38560Y329739D03*
X35500Y340500D03*
Y335000D03*
X44220Y341008D03*
X44500Y344000D03*
Y355500D03*
X37400Y359900D03*
X44500Y348000D03*
X44525Y360000D03*
X35100Y352400D03*
X44500Y351600D03*
X38200Y364855D03*
X35900Y363025D03*
X37800Y371225D03*
X44525Y364000D03*
Y368000D03*
X37300Y375000D03*
X44525Y376000D03*
X37875Y377925D03*
X44525Y387800D03*
X37735Y391200D03*
X44525Y391650D03*
X35101Y381610D03*
X44525Y384000D03*
X37020Y385600D03*
X47075Y391730D03*
X44500Y380000D03*
X44490Y397850D03*
X44525Y394150D03*
X36911Y394915D03*
X37067Y398337D03*
X44341Y406480D03*
X44330Y401450D03*
X36600Y408600D03*
X39530Y409100D03*
X42900Y412900D03*
X46100Y412700D03*
X41200Y429100D03*
X43600Y422800D03*
X42200Y435900D03*
X38000Y428800D03*
X48050Y436350D03*
X45100Y435800D03*
X46100Y422800D03*
X40848Y448440D03*
X62218Y3000D03*
X54200Y25400D03*
X53000Y41500D03*
X53600Y44100D03*
X56348Y36210D03*
X59425Y53075D03*
X50508Y57459D03*
X50710Y54724D03*
X57500Y75500D03*
X60000D03*
X55000Y76000D03*
X63086Y65762D03*
X52120Y78373D03*
X59240Y67242D03*
X52502Y80978D03*
X53434Y106562D03*
X53400Y102788D03*
X52155Y121218D03*
X60112Y113992D03*
X53267Y109094D03*
X59945Y117795D03*
Y120630D03*
X60411Y130200D03*
X60800Y137000D03*
X61123Y133070D03*
X52876Y195712D03*
X52410Y186900D03*
X59700Y196200D03*
X52410Y190190D03*
X57141Y209341D03*
X59900Y199900D03*
X64050Y201010D03*
X52948Y200700D03*
X58000Y217700D03*
X58823Y213531D03*
X52000Y230400D03*
X63300Y237600D03*
X51600Y241200D03*
X59850Y235830D03*
X51010Y233570D03*
X49700Y242900D03*
X50567Y238630D03*
X50700Y250400D03*
X62500Y272500D03*
X61200Y282600D03*
X58654Y290605D03*
X58900Y288075D03*
X54660Y311660D03*
X60561Y314843D03*
X60613Y312012D03*
X60600Y318000D03*
X64230Y303210D03*
X56600Y324300D03*
X52800Y322400D03*
X63000Y324100D03*
X56600Y318000D03*
X52820Y325200D03*
X60225Y336099D03*
X57400Y345400D03*
X58035Y370100D03*
X54400Y374700D03*
X55294Y369729D03*
X52475Y364000D03*
X52765Y390200D03*
X59500Y394000D03*
X58620Y408779D03*
X63200Y408600D03*
X52330Y413350D03*
X59097Y433502D03*
X57470Y426544D03*
X51535D03*
X59511Y424477D03*
X60622Y431273D03*
X64122D03*
X56250Y424200D03*
X52750D03*
X56482Y450344D03*
X62600Y450700D03*
X54100Y448600D03*
X56500Y447600D03*
X63563Y460100D03*
X56476D03*
X56482Y456844D03*
Y453344D03*
X63569Y456844D03*
Y453344D03*
X76500Y66500D03*
X65928Y76500D03*
X68500Y66500D03*
X75280Y75704D03*
X72500Y66500D03*
X74757Y89745D03*
Y92745D03*
Y86745D03*
Y83745D03*
X66830Y122329D03*
X66900Y125300D03*
X72044Y132312D03*
X71970Y135893D03*
X69195Y135799D03*
X69285Y132321D03*
X67126Y128100D03*
X66874Y130590D03*
X68335Y141369D03*
X68375Y144100D03*
X68434Y149506D03*
X68432Y152147D03*
X70580Y167179D03*
X72300Y159400D03*
X68600Y159160D03*
X76442Y166907D03*
X73550Y166680D03*
X68960Y173300D03*
X75284Y180800D03*
X71124Y178565D03*
X65301Y187762D03*
X67486Y186414D03*
X71146Y186489D03*
X71370Y188993D03*
X67386Y191935D03*
X67486Y188977D03*
X74046Y186490D03*
X71600Y200900D03*
X72150Y204810D03*
X76670Y208772D03*
X72500Y214000D03*
X70453Y222900D03*
X74583Y217314D03*
X72000Y235925D03*
X71100Y233575D03*
X67700Y229725D03*
X65801Y253145D03*
X77010Y256645D03*
X65755Y256045D03*
X76200Y247400D03*
X73011Y246365D03*
X77384Y253769D03*
X68800Y253300D03*
X65800Y260875D03*
X76500Y270700D03*
X74000Y270800D03*
X68990Y260465D03*
X77437Y262760D03*
X76284Y280470D03*
X78600Y283970D03*
X75960Y284049D03*
X65100Y282475D03*
X75870Y290700D03*
X78770Y290708D03*
X75300Y305150D03*
X69500Y308700D03*
X64567Y306665D03*
X73400Y313700D03*
X77500Y316100D03*
X73000Y323400D03*
X68500Y325100D03*
X81000Y321900D03*
X76900Y323000D03*
X76500Y325500D03*
X78700Y340000D03*
X78900Y336600D03*
X71700Y340600D03*
X67900Y400525D03*
X79000Y395500D03*
X73976Y408665D03*
X69057Y419700D03*
X77860Y408678D03*
X77592Y413437D03*
X69139Y413452D03*
X66319Y413492D03*
X74782Y413800D03*
X67000Y408800D03*
X69700D03*
X78800Y423800D03*
X66297Y433002D03*
X71035Y426543D03*
X76770D03*
X69030Y422653D03*
X68100Y425400D03*
X71200Y431700D03*
X72150Y424199D03*
X75650D03*
X77600Y431400D03*
X79010Y445750D03*
X72800Y437900D03*
X70650Y460100D03*
X77500D03*
X82218Y3000D03*
X91700Y66500D03*
X86500Y75000D03*
X84500Y66500D03*
X90151Y68985D03*
X91358Y89745D03*
Y92745D03*
Y86745D03*
Y83745D03*
X86700Y119100D03*
X92500Y116200D03*
X88500Y128000D03*
X89256Y135056D03*
X86100Y153340D03*
X89170Y141540D03*
X89200Y138800D03*
X86100Y155840D03*
X83410Y161020D03*
X86100Y158390D03*
X83520Y158520D03*
X81500Y176515D03*
X81800Y188500D03*
X80788Y190812D03*
X82370Y197010D03*
X90900Y222850D03*
X81600Y241500D03*
X87500Y237300D03*
X91300Y252900D03*
X80300Y243700D03*
X80270Y247830D03*
X84000Y261375D03*
X83500Y266900D03*
X84016Y258230D03*
X91500Y267000D03*
X85672Y283985D03*
X92300Y282100D03*
X81864Y297900D03*
X85600Y298100D03*
X90923Y293520D03*
X82200Y308700D03*
X82022Y303350D03*
X84126Y311790D03*
X79600Y312000D03*
X85500Y323400D03*
Y326700D03*
X92698Y323224D03*
X93288Y330289D03*
X85600Y335000D03*
X81900Y337100D03*
X81700Y342600D03*
X86300Y397600D03*
X89487Y408435D03*
X87600Y414500D03*
X87800Y410300D03*
X84801Y409760D03*
X92500Y408630D03*
X86481Y407871D03*
X96030Y409400D03*
X81552Y409660D03*
X84320Y430510D03*
X93259Y424200D03*
X88565Y426535D03*
X79600Y426400D03*
X92001Y450402D03*
X82256Y445577D03*
X85276Y445550D03*
X81990Y448085D03*
X85490D03*
X92870Y437831D03*
X89700Y437900D03*
X84823Y460100D03*
X91909Y458275D03*
X92801Y452793D03*
X102218Y3000D03*
X107000Y44500D03*
X104575Y62369D03*
X102190Y63225D03*
X104600Y50501D03*
X104575Y67581D03*
X95400Y66500D03*
X98000Y75500D03*
X98500Y66500D03*
X102190Y66725D03*
X111000Y77000D03*
X104500Y73500D03*
X107124Y71004D03*
X108800Y91900D03*
X104425Y82500D03*
X110950Y82050D03*
X106000Y91900D03*
X108727Y99153D03*
X100000Y98500D03*
X111075Y104600D03*
X105916Y109952D03*
X101230Y127010D03*
X96400Y137475D03*
X102999Y131799D03*
X108270Y138630D03*
X95950Y152900D03*
X95944Y149687D03*
X103500Y240619D03*
X98720Y236980D03*
X103580Y237400D03*
X106600Y253689D03*
X95300Y247100D03*
X102600Y267000D03*
X107200Y265000D03*
X106800Y262076D03*
X97440Y283590D03*
X106574Y280028D03*
X106100Y282900D03*
X100700Y293600D03*
X108551Y294241D03*
X99990Y311200D03*
X105000Y311900D03*
X99990Y307900D03*
X105100Y309300D03*
X94400Y311100D03*
Y307200D03*
X100500Y328547D03*
X96457Y323194D03*
X105755Y327719D03*
X103000Y323800D03*
X95060Y327625D03*
X106852Y323292D03*
X97800Y325700D03*
X97608Y335534D03*
X99026Y338368D03*
X103180Y336286D03*
X108108Y395100D03*
X103400Y420000D03*
X95280Y412500D03*
X98100Y412400D03*
X105500Y418200D03*
X100457Y409100D03*
X108701Y418300D03*
X98300Y407600D03*
X108336Y411547D03*
X108500Y408680D03*
X109048Y425853D03*
X104112Y422946D03*
X103461Y425875D03*
X95845Y424755D03*
X97156Y450437D03*
X94560Y443287D03*
X100225Y443127D03*
X106700Y447730D03*
X95770Y437920D03*
X95870Y445483D03*
X99370D03*
X103900Y447640D03*
X98996Y458275D03*
X106083D03*
X96301Y452793D03*
X122218Y3000D03*
X111000Y44600D03*
X115000Y44500D03*
X125800Y47330D03*
X122500Y58000D03*
X112800Y60400D03*
X112600Y52800D03*
X109121Y69500D03*
X119700Y89200D03*
X116560Y88651D03*
X123710Y82300D03*
X123740Y79791D03*
X115025Y104800D03*
X120726Y105000D03*
X115200Y98200D03*
X123325Y111000D03*
X120724Y108937D03*
X120626Y123500D03*
X112000D03*
X116200Y115100D03*
X109350Y115501D03*
X109200Y118500D03*
X120500Y115525D03*
X109200Y128500D03*
X118990Y131580D03*
X109670Y136060D03*
X118692Y137304D03*
X120800Y147200D03*
X117800D03*
X113000Y160700D03*
X115400Y159500D03*
X122900Y170100D03*
X123120Y213088D03*
X119060Y199695D03*
X123790Y227656D03*
X113590Y245170D03*
X118300Y237500D03*
X123690Y230156D03*
X117840Y242200D03*
X121200Y234890D03*
X112200Y234520D03*
X116143Y230790D03*
X112900Y239200D03*
X111400Y254680D03*
X122876Y245300D03*
X120020Y254430D03*
X119105Y251511D03*
X121720Y265330D03*
X117400Y266500D03*
X109800Y264928D03*
X111600Y262730D03*
X111100Y273700D03*
X111600Y284000D03*
X120070Y273700D03*
X115000D03*
X111177Y293471D03*
X122957Y300991D03*
X123100Y295974D03*
X120600Y293471D03*
X110565Y296331D03*
X118009Y313810D03*
Y311200D03*
X124935Y324900D03*
X115535Y335235D03*
X124300Y348800D03*
X115600Y337900D03*
X114700Y351200D03*
X121200Y359200D03*
X111330Y357800D03*
X120200Y361600D03*
X114700Y348500D03*
X111460Y361770D03*
X115000Y369500D03*
X111950Y371200D03*
X122047Y372260D03*
X125650Y368650D03*
X122330Y364670D03*
X111869Y365454D03*
X119200Y389700D03*
X117410Y381350D03*
X110900Y378500D03*
X123100Y390600D03*
X122600Y394600D03*
X119026Y393332D03*
X119791Y412301D03*
X112800Y421600D03*
X113000Y416200D03*
X116632Y411500D03*
X122498Y419675D03*
X112796Y412490D03*
X119500Y433600D03*
X111510Y434710D03*
X121700Y424005D03*
X123170Y433200D03*
X127900Y45000D03*
X129575Y57375D03*
X133000Y59900D03*
X140730Y72600D03*
X130500Y74700D03*
X129300Y82650D03*
X131470Y81260D03*
X129500Y91475D03*
X129328Y122500D03*
X126575Y111416D03*
X131528Y114271D03*
X135500Y138000D03*
Y135000D03*
X134400Y127652D03*
X131700Y131000D03*
X132828Y138400D03*
X133500Y146800D03*
X138458Y146458D03*
X133500Y149385D03*
X124500Y167100D03*
X132500Y167300D03*
X133690Y158100D03*
X136190D03*
X126300Y176575D03*
X126500Y174000D03*
X137900Y179160D03*
X135300Y175100D03*
X125700Y183700D03*
X129810Y191310D03*
X135000Y206900D03*
X124338Y204742D03*
X124779Y201633D03*
X126153Y199079D03*
X135000Y221200D03*
X132500Y221900D03*
X134891Y225171D03*
X124226Y225194D03*
X134358Y230069D03*
X130167Y234733D03*
X138000Y244600D03*
X128900Y255898D03*
X133000Y256100D03*
X128760Y265726D03*
X127600Y259700D03*
X131216Y280187D03*
X135315Y279813D03*
X125100Y273720D03*
X128760Y273701D03*
X137083Y278045D03*
X137196Y274491D03*
X132420Y273811D03*
X138600Y295900D03*
X124016Y313784D03*
X135462Y313727D03*
X124100Y311100D03*
X136100Y334000D03*
X129800Y325800D03*
X138590Y345710D03*
X124400Y345300D03*
X125910Y335006D03*
X125900Y337600D03*
X133300Y334100D03*
X136000Y341000D03*
X133100Y358900D03*
X132600Y350090D03*
X124350Y352450D03*
X129776Y374500D03*
X138700Y376600D03*
X133640Y390524D03*
X126340Y382700D03*
X125174Y393916D03*
X124287Y406262D03*
X127300Y392600D03*
X135300Y399900D03*
X137900Y399500D03*
X131540Y394690D03*
X132700Y402700D03*
X129900Y415583D03*
X133500Y409110D03*
X129135Y410250D03*
X133070Y420874D03*
X134300Y416414D03*
X136230Y423935D03*
X128866Y433066D03*
X135350Y433016D03*
X124500Y424005D03*
X132070Y433110D03*
X133572Y423935D03*
X125930Y433110D03*
X138750Y451500D03*
X138500Y457250D03*
X138750Y454500D03*
X142218Y3000D03*
X147947Y9800D03*
X146800Y79000D03*
X152800Y75600D03*
X140869Y89055D03*
X145000Y90700D03*
X145100Y87400D03*
X142400Y91300D03*
X141100Y86500D03*
X141700Y96929D03*
X140869Y104803D03*
Y120551D03*
Y112677D03*
X148819Y123197D03*
X143400Y121700D03*
X141220Y123070D03*
X147600Y117000D03*
X151800Y116500D03*
X152800Y111600D03*
X148819Y125697D03*
X149800Y138100D03*
Y135100D03*
X145185Y134214D03*
X142892Y136645D03*
X142000Y146000D03*
X143269Y150456D03*
X150155Y145086D03*
X152556Y147683D03*
X148429Y147682D03*
X148400Y155765D03*
X144500Y169570D03*
X146300Y161010D03*
X153134Y178572D03*
X140554Y168887D03*
X153200Y170990D03*
X140554Y171688D03*
X146882Y177501D03*
X150619Y178646D03*
X145296Y188835D03*
X140830Y192530D03*
X153051Y187354D03*
X150005Y184973D03*
X149100Y189963D03*
X144280Y195130D03*
X151940Y203710D03*
X143980Y199674D03*
X147800Y200789D03*
X140903Y199421D03*
X143742Y203395D03*
X152500Y199500D03*
X146390Y224040D03*
X146000Y216350D03*
X141954Y224274D03*
X142300Y216300D03*
X145500Y227700D03*
X142702Y227817D03*
X153100Y234800D03*
X149862Y243788D03*
X142085Y230549D03*
X151040Y237870D03*
X145250Y256890D03*
X145580Y248082D03*
X141280Y256310D03*
X142780Y266830D03*
X149215Y267745D03*
X152400Y284400D03*
X150240Y277940D03*
X152400Y293400D03*
X152500Y289425D03*
X150293Y302117D03*
X147500Y289405D03*
X141890Y310570D03*
X150293Y315493D03*
X151320Y322700D03*
X142500Y345800D03*
X148600Y336300D03*
X142202Y334000D03*
X142300Y336700D03*
X144800D03*
X144700Y334100D03*
X153419Y341978D03*
X141045Y355309D03*
X150900Y360325D03*
X151695Y357900D03*
X149500Y356700D03*
X141000Y358500D03*
X140700Y370252D03*
X145703Y370700D03*
X139200Y372510D03*
X149000Y383070D03*
X152100Y378400D03*
X152500Y382600D03*
X150820Y387325D03*
X143300Y396400D03*
X140300Y395100D03*
X139400Y392460D03*
X151265Y399500D03*
X142511Y393690D03*
X146600Y410600D03*
X153079Y412000D03*
X139700Y415100D03*
X150000Y414750D03*
X143000Y414600D03*
X140600Y412300D03*
X152100Y425700D03*
X145365Y426050D03*
X148060Y423500D03*
X148100Y433400D03*
X152200Y423100D03*
X148041Y426700D03*
X138987Y423935D03*
X151398Y449930D03*
X149041Y458750D03*
X162218Y3000D03*
X165700Y11100D03*
X166719Y75874D03*
X158246Y78872D03*
X156710Y73420D03*
X168297Y93976D03*
X164429Y93991D03*
X158873Y93976D03*
X166500Y96400D03*
X163423Y96281D03*
X159923D03*
X166200Y105500D03*
X158420Y116610D03*
X159700Y112000D03*
X155530Y116640D03*
X156286Y124903D03*
X156200Y111600D03*
X162657Y117297D03*
X166700Y132360D03*
X156406Y129203D03*
X162419Y131032D03*
X166733Y128700D03*
X153954Y145086D03*
X161900Y150500D03*
X165690Y149622D03*
X159328Y160847D03*
X156481Y155933D03*
X162200Y158200D03*
X159900Y155600D03*
X161240Y177820D03*
X161237Y181735D03*
Y185815D03*
X161240Y190477D03*
X166361Y209794D03*
X156467Y203500D03*
X162594Y212585D03*
Y210085D03*
X166140Y205955D03*
X165381Y201274D03*
X166308Y225189D03*
X162653Y218843D03*
X159643Y226484D03*
X162200Y221376D03*
X163500Y229184D03*
X167200Y222600D03*
X155800Y234700D03*
X161200Y233600D03*
X165500Y236100D03*
X157200Y240000D03*
X156970Y255000D03*
X165013Y254986D03*
X160973D03*
X164500Y266000D03*
X163690Y268610D03*
X160590Y263300D03*
X156970Y263250D03*
X164800Y263300D03*
X158750Y284949D03*
X168392Y298493D03*
X160850Y301344D03*
X168300Y301100D03*
X162100Y291600D03*
X161400Y307600D03*
X162160Y313560D03*
X170800Y317600D03*
X164500Y314800D03*
X155000Y321100D03*
X164790Y341100D03*
X168557Y341221D03*
X158459Y340898D03*
X158467Y344067D03*
X163800Y356800D03*
X161154Y376704D03*
X156300Y376300D03*
X164318Y389102D03*
X157282D03*
X156900Y385700D03*
X154500Y387350D03*
X159050Y387334D03*
X162550D03*
X165500Y386000D03*
X165501Y382800D03*
X158200Y381400D03*
X155452Y401000D03*
X154000Y414750D03*
X160540Y416912D03*
X162100Y414000D03*
X165194Y428688D03*
X157294Y435623D03*
X156101Y425100D03*
X167008Y430718D03*
X165500Y433100D03*
X167865Y427771D03*
X163700Y422119D03*
X159396Y449408D03*
X160700Y445550D03*
X158100Y442700D03*
X160852Y460118D03*
X168029Y456660D03*
X157500Y453390D03*
X182218Y3000D03*
X176900Y14625D03*
X178200Y76145D03*
X175700Y76245D03*
X173853Y93991D03*
X182925Y84300D03*
X179900Y91300D03*
X181960Y99260D03*
X169700Y102250D03*
X176300Y98700D03*
X172847Y96281D03*
X169347D03*
X180333Y114292D03*
X179500Y116800D03*
X182000Y117200D03*
X171600Y114000D03*
X182865Y113706D03*
X174600Y114000D03*
X169100Y113900D03*
X182103Y132294D03*
X182108Y129094D03*
X170867Y128211D03*
X178290Y128824D03*
X174553Y128728D03*
X176550Y125210D03*
X178284Y132394D03*
X170610Y131900D03*
X174436Y132394D03*
X168800Y126800D03*
X172100Y146300D03*
X176000Y140500D03*
X172890Y153260D03*
X171700Y156900D03*
X169500Y180200D03*
X170800Y193100D03*
X172621Y208300D03*
X173800Y225400D03*
X170400Y214700D03*
X172400Y220700D03*
X175300Y240000D03*
X174400Y249136D03*
Y254736D03*
X179846Y255150D03*
X180458Y258825D03*
X174400Y251936D03*
X176900Y270100D03*
X174292Y263300D03*
X171592Y263312D03*
X168710Y272256D03*
X172977Y277000D03*
X182435Y281797D03*
X179217Y278528D03*
X168656Y275156D03*
X181194Y294074D03*
X182232Y296424D03*
X173880Y312430D03*
X174232Y304333D03*
X176563Y310917D03*
X176533Y314049D03*
X170550Y304050D03*
X169077Y308677D03*
X170561Y306631D03*
X182372Y325961D03*
X181050Y332250D03*
X171098Y341224D03*
X182700Y342216D03*
X169200Y349400D03*
X180350Y368650D03*
X177500Y369100D03*
X177082Y387402D03*
X178850Y385634D03*
X182350D03*
X169669Y399419D03*
X172550Y398690D03*
X172530Y420950D03*
X182750Y426750D03*
X172530Y429470D03*
X184480Y429370D03*
X171400Y450600D03*
X193100Y69100D03*
X189400Y69600D03*
X187272Y84472D03*
X191312Y84512D03*
X190200Y100500D03*
X198281Y101286D03*
X184800Y100300D03*
X187700Y99000D03*
X187400Y101500D03*
X190800Y117200D03*
X193096Y115600D03*
X186891Y113991D03*
X190744Y114456D03*
X187069Y116800D03*
X184729Y115820D03*
X187360Y132425D03*
X187435Y129623D03*
X195983Y132294D03*
X191482Y129294D03*
X195983D03*
X186200Y125600D03*
X184000Y140500D03*
X196577Y141185D03*
X189700Y140400D03*
X196827Y240349D03*
X191693Y236370D03*
X185897Y249936D03*
X196240Y253430D03*
X193084Y257400D03*
X194567Y255288D03*
X187400Y255700D03*
X191583Y261363D03*
X190900Y271700D03*
X193386Y269142D03*
X184200Y264900D03*
X185000Y270700D03*
X189228Y280655D03*
X195370Y273297D03*
X183625Y273500D03*
X196200Y278200D03*
X196100Y281820D03*
X187623Y297475D03*
X192380Y291900D03*
X196443Y294065D03*
X191199Y300200D03*
X185725Y307320D03*
X192448Y308314D03*
X195031Y307182D03*
X194600Y313300D03*
X197853Y307200D03*
X197155Y314223D03*
X188546Y326356D03*
X190465Y344426D03*
X190600Y337900D03*
X183800Y345400D03*
X197775Y346617D03*
X194800Y341700D03*
X191408Y357451D03*
X197450Y356560D03*
X190922Y350990D03*
X191420Y354710D03*
X190965Y348090D03*
X197711Y349250D03*
X195000Y373900D03*
X187400Y379400D03*
X197400Y367600D03*
Y370250D03*
X184118Y387402D03*
X197620Y385425D03*
X187300Y384300D03*
X197660Y390870D03*
X190050Y389140D03*
X190100Y392270D03*
X191843Y403995D03*
X189054Y397500D03*
X194500Y402600D03*
X195800Y396780D03*
X200274Y410960D03*
X185875Y415051D03*
X185245Y417500D03*
X190370Y422490D03*
X195000Y422540D03*
X199940Y423700D03*
X197600Y415400D03*
X190270Y409962D03*
X189762Y429177D03*
X195300Y432327D03*
X189766Y432050D03*
X189838Y434910D03*
X186720Y432490D03*
X186300Y448700D03*
X185000Y451500D03*
X189600Y459800D03*
X185000Y454000D03*
Y456500D03*
X191780Y453300D03*
Y456700D03*
X202218Y3000D03*
X207700Y59100D03*
X211400Y59238D03*
X204300Y60600D03*
X201500Y61000D03*
X209142Y53664D03*
X213100Y69300D03*
X204100Y67400D03*
X209500Y92326D03*
X211800Y93870D03*
X201900Y83300D03*
X209824Y106122D03*
X203600Y117000D03*
X199940Y117500D03*
X211370Y117000D03*
X208200Y111760D03*
X203970Y125500D03*
X199985Y132294D03*
X212757Y127064D03*
X212727Y129654D03*
X208627Y132394D03*
X208576Y128957D03*
X204120Y132294D03*
X200000Y128764D03*
X208500Y126057D03*
X212727Y132154D03*
X211200Y140513D03*
X211490Y143700D03*
X205598Y140480D03*
X203542Y213254D03*
X206200Y255385D03*
X198990Y247811D03*
X200680Y257540D03*
X206051Y247911D03*
X211265Y267300D03*
X205500Y258300D03*
X201100Y265120D03*
X214034Y261482D03*
X201000Y262500D03*
X203090Y269229D03*
X205590Y269129D03*
X205900Y266130D03*
X205130Y282000D03*
X204207Y278200D03*
X213258Y273265D03*
X207220Y301180D03*
X204560Y301130D03*
X212911Y293869D03*
X206430Y298780D03*
X199729Y314565D03*
X208628Y324665D03*
X200300Y328800D03*
X207750Y366500D03*
X208000Y373240D03*
X208360Y384890D03*
X208565Y404501D03*
X200222Y398150D03*
X213200Y399166D03*
X199880Y402846D03*
X203180Y416371D03*
X207539Y408686D03*
X200000Y407040D03*
X205223Y422665D03*
X207278Y416022D03*
X206150Y412821D03*
X198600Y426600D03*
X202513Y434800D03*
X198405D03*
X211865Y444520D03*
X199000Y444500D03*
X205200Y445400D03*
X213225Y442220D03*
X200000Y455800D03*
X209300Y457700D03*
X222218Y3000D03*
X214306Y62233D03*
X229900Y61000D03*
X227547Y74275D03*
X219600Y74000D03*
X215800Y69300D03*
X218600D03*
X224000Y74275D03*
X224330Y83210D03*
X227760Y82524D03*
X224958Y107236D03*
X216400Y106400D03*
X226040Y101220D03*
X222890Y101240D03*
X215294Y117094D03*
X226887Y117297D03*
X223300Y117400D03*
X221500Y125100D03*
X217262Y129294D03*
X225284Y132294D03*
X229342Y129240D03*
X221278Y129294D03*
X225284D03*
X217262Y132294D03*
X221278D03*
X225300Y125200D03*
X227700Y151900D03*
X221000Y243000D03*
X220100Y237200D03*
X223800Y254800D03*
X227316Y256700D03*
X215100Y244100D03*
X215500Y247111D03*
X216800Y255550D03*
X215510Y253310D03*
X225275Y246000D03*
X217500Y264000D03*
X230196Y267477D03*
X219900Y267100D03*
X220866Y272160D03*
X227232Y270539D03*
X226405Y266335D03*
X222833Y261668D03*
X225441Y282267D03*
X219722Y286728D03*
X226500Y273000D03*
X229220Y283250D03*
X223672Y290735D03*
X215600Y316800D03*
X213610Y308800D03*
X214400Y303997D03*
X216384Y312216D03*
X228800Y312100D03*
X226100Y325065D03*
X217300Y322800D03*
X225650Y337520D03*
X221000Y343800D03*
X216405Y335970D03*
X214175Y333740D03*
X228230Y340040D03*
X221000Y352000D03*
X223160Y362600D03*
X213490Y373690D03*
X226710Y364815D03*
X223420Y367080D03*
X222575Y387625D03*
X227206Y400100D03*
X217390Y401340D03*
X222986Y400323D03*
X220134Y400780D03*
X222225Y407650D03*
X216725D03*
X219050Y418850D03*
X217725Y410150D03*
X221225D03*
X226830Y435170D03*
X225000Y433100D03*
X219250Y422150D03*
X213900Y436000D03*
X217100Y436100D03*
X218085Y444520D03*
X224000Y449100D03*
X216725Y442220D03*
X222200Y458700D03*
X215000Y458600D03*
X242218Y3000D03*
X233000Y47100D03*
X237000Y47200D03*
X230800Y57613D03*
X240000Y67400D03*
X239347Y79457D03*
X230600Y91700D03*
X239660Y91920D03*
X232150Y82480D03*
X235630Y104990D03*
X231592Y110500D03*
X237280Y107510D03*
X229000Y101000D03*
X240160Y107000D03*
X240710Y99570D03*
X232325Y101230D03*
X236648Y100739D03*
X242812Y117501D03*
X238900Y114800D03*
X234500Y117500D03*
X230293Y117417D03*
X239900Y117550D03*
X239206Y112300D03*
X242800Y132200D03*
X231100Y125600D03*
X233511Y132594D03*
X234900Y126100D03*
X229396Y132294D03*
X233511Y129594D03*
X242500Y129000D03*
X242195Y141003D03*
X232384Y148884D03*
X230535Y244564D03*
X237700Y257387D03*
X237730Y248085D03*
X242690Y255300D03*
X230000Y255700D03*
X232773Y269532D03*
X232300Y261200D03*
X239298Y268800D03*
X242940Y268500D03*
X233033Y266483D03*
X229630Y264404D03*
X242087Y271427D03*
X238531Y263081D03*
X231900Y272700D03*
X241188Y279347D03*
X241263Y282654D03*
X234500Y293500D03*
X242700Y306800D03*
X228800Y302700D03*
X236688Y311217D03*
X238400Y304200D03*
X228800Y305500D03*
X235400Y303800D03*
X241400Y328100D03*
X242592Y330683D03*
X243010Y323400D03*
X230445Y325945D03*
X233468Y341046D03*
X235000Y335300D03*
X231689Y334896D03*
X233500Y346911D03*
Y343911D03*
X233300Y356890D03*
X231500Y352500D03*
X233650Y359628D03*
X233800Y354300D03*
X233600Y371500D03*
X230287Y373100D03*
X233800Y390118D03*
X228230Y390390D03*
X232470Y382280D03*
X233600Y377300D03*
X233790Y384490D03*
X236670Y394550D03*
X241231Y407285D03*
X236860Y407300D03*
X229900Y436600D03*
X236900Y440565D03*
X239500Y447750D03*
X235400Y451600D03*
X231250Y447000D03*
X235200Y449100D03*
X231400Y449500D03*
X241436Y445784D03*
X240200Y450650D03*
X228200Y459100D03*
X236221Y454400D03*
X240010Y456000D03*
X240210Y453400D03*
X231400Y452000D03*
X248359Y46559D03*
X249475Y55812D03*
X256000Y56000D03*
X248700Y75900D03*
X255750Y77350D03*
X253000Y77500D03*
X250000Y73000D03*
X250900Y90900D03*
X257800Y82800D03*
X256900Y87300D03*
X251200Y93800D03*
X254397Y103697D03*
X244987Y103528D03*
X251113Y102919D03*
X252300Y107664D03*
X245391Y99589D03*
X251900Y100100D03*
X255213Y106099D03*
X249988Y105792D03*
X246488D03*
X244208Y97302D03*
X247200Y117400D03*
X253100Y119900D03*
X245310Y113910D03*
X252374Y132159D03*
X245500Y127800D03*
X245520Y130600D03*
X258500Y146400D03*
X251354Y152877D03*
X249300Y237600D03*
X247689Y247929D03*
X253110Y254909D03*
X253100Y257800D03*
X252639Y247885D03*
X256700Y263800D03*
X255700Y260000D03*
X247470Y269990D03*
X253388Y273655D03*
X250288Y273581D03*
X251459Y286542D03*
Y283542D03*
X257145Y279700D03*
X246200Y299700D03*
X246514Y294325D03*
Y296825D03*
X258100Y295080D03*
X254355Y300577D03*
X247923Y316400D03*
X245900Y305000D03*
X257900Y312100D03*
X248900Y304900D03*
X247923Y319000D03*
X253320Y323327D03*
X256124Y336355D03*
X243700Y372730D03*
X244790Y375910D03*
X243410Y381323D03*
X248800Y385700D03*
X249400Y410300D03*
X252350Y412850D03*
X257810Y435100D03*
X245300Y445800D03*
X246700Y451500D03*
X246500Y448500D03*
X243375Y448375D03*
X246700Y454100D03*
X262218Y3000D03*
X267022Y12166D03*
X269095Y34625D03*
X260970Y42441D03*
X259000Y47500D03*
X267939Y41122D03*
X268500Y45500D03*
X268675Y74400D03*
X267168Y93768D03*
X260132D03*
X259894Y90072D03*
X263102Y91725D03*
X272505Y83545D03*
X260050Y87026D03*
X259759Y103651D03*
X259500Y101100D03*
X265801Y106040D03*
X260970Y98600D03*
X258713Y106099D03*
X264989Y101732D03*
X268435Y121476D03*
X271602Y121400D03*
X269561Y130987D03*
X271300Y132900D03*
X269493Y138604D03*
X260200Y132395D03*
X260388Y125001D03*
X263294Y153366D03*
X263030Y150846D03*
X269004Y144450D03*
Y141950D03*
X269133Y164982D03*
X265226D03*
X268339Y222126D03*
X272300Y251000D03*
X258628Y247600D03*
X258475Y254872D03*
X259500Y263700D03*
X262730Y267600D03*
X258000Y266300D03*
X266600Y268700D03*
X262700Y265100D03*
X258000Y284900D03*
X262100Y280700D03*
X266200Y300500D03*
Y294800D03*
X261500Y290440D03*
X266300Y307500D03*
X262310Y311225D03*
X264265Y315817D03*
X262930Y325300D03*
X261300Y334100D03*
X259420Y345930D03*
Y343230D03*
Y340630D03*
X265922Y354238D03*
X273580Y354250D03*
X271990Y362360D03*
X272100Y396300D03*
X274190Y408900D03*
X265100Y395100D03*
X272400Y392400D03*
X269700Y411379D03*
X271500Y418300D03*
X265100Y424000D03*
X266300Y435900D03*
X267100Y432900D03*
X263800Y430300D03*
X272999Y430500D03*
X271500Y446800D03*
X271710Y449840D03*
X266727Y443185D03*
X261700Y439700D03*
X265130Y440070D03*
X261100Y443500D03*
X269534Y459061D03*
X269561Y456044D03*
X282218Y3000D03*
X277000Y41982D03*
X286000Y47000D03*
X282440Y51941D03*
X274219Y51641D03*
X279934Y51688D03*
X286000Y67975D03*
X279800Y72700D03*
X274400Y90019D03*
X290000Y82000D03*
X273400Y92800D03*
X276400Y92300D03*
X287578Y84092D03*
X283500Y89500D03*
X277505Y83545D03*
X282505D03*
X278300Y95019D03*
X274760Y105140D03*
X275386Y102710D03*
X280910Y102880D03*
X279200Y114100D03*
X288116Y120306D03*
X285250Y117250D03*
X274200Y109500D03*
X280400Y126000D03*
X274500Y131629D03*
X279600Y131400D03*
X283500Y126000D03*
X275960Y126010D03*
X273450Y125050D03*
X287796Y131542D03*
X288280Y126212D03*
X280744Y142070D03*
X283248Y142046D03*
X280616Y150971D03*
X283616D03*
X287555Y142419D03*
X285899Y153542D03*
X283399D03*
X278155Y176085D03*
X279457Y171318D03*
X286000Y242100D03*
X279983Y235254D03*
X282483D03*
X283974Y251372D03*
X286800Y251400D03*
X276200Y251500D03*
X280082Y251328D03*
X280030Y267098D03*
Y264098D03*
X284357Y267027D03*
Y264027D03*
X285911Y269899D03*
X281889D03*
X287755Y287538D03*
X281889Y287636D03*
X282911Y279569D03*
X285911D03*
X287507Y301596D03*
X281300Y308800D03*
X287050Y305850D03*
X289939Y309060D03*
X276660Y316900D03*
X276155Y329999D03*
X273355Y330001D03*
X286372Y320700D03*
X289600Y322253D03*
X286372Y326768D03*
X285860Y336131D03*
X277500Y348469D03*
X275520Y357910D03*
X277290Y355820D03*
X277572Y351198D03*
X276100Y375900D03*
X287725Y363473D03*
X276145Y366455D03*
X276400Y370400D03*
X276100Y381500D03*
X284614Y387136D03*
X283664Y379236D03*
X273100Y381500D03*
X283973Y382553D03*
X285191Y390840D03*
X287630Y389378D03*
X277700Y406100D03*
X287476Y396680D03*
X281300Y419300D03*
X278200Y408700D03*
X278900Y421400D03*
X281300Y416200D03*
X277700Y412580D03*
X287500Y416100D03*
X278409Y433722D03*
X276400Y431810D03*
X275100Y427682D03*
X274619Y424725D03*
X283622Y447155D03*
X275138Y451215D03*
X276632Y439502D03*
X283674Y449975D03*
X277563Y460028D03*
X283707Y459398D03*
X283715Y452769D03*
X302218Y3000D03*
X300600Y10591D03*
X288856Y12166D03*
X295402Y48051D03*
X290245Y46978D03*
X297466Y51521D03*
X297575Y73738D03*
X293773Y73530D03*
X300856Y104059D03*
X301151Y108649D03*
X294600Y106900D03*
X298575Y101900D03*
X304000Y116500D03*
X294800Y111800D03*
X298975Y118900D03*
X301000Y121016D03*
X300500Y125000D03*
X295075Y119100D03*
X301936Y135797D03*
X294200Y128800D03*
X301000Y129900D03*
X290200Y129500D03*
X293693Y152232D03*
X290889Y152318D03*
X298005Y151118D03*
Y148618D03*
Y146118D03*
X292204Y142610D03*
X301936Y143897D03*
X301507Y195435D03*
X301120Y226421D03*
X296734Y216079D03*
X301120Y229810D03*
X290586Y234844D03*
X288086D03*
X301120Y235626D03*
Y238765D03*
X299138Y244513D03*
X302687Y275497D03*
X291500Y287670D03*
Y285170D03*
X298840Y279640D03*
X291000Y297700D03*
X291300Y315900D03*
X296938Y325700D03*
X301500Y326500D03*
X290120Y339370D03*
X290000Y335600D03*
X300700Y341300D03*
X296780Y371500D03*
X298748Y390118D03*
X298152Y393332D03*
X297399Y397382D03*
X292700Y403700D03*
X290800Y438300D03*
X291623Y447747D03*
X291703Y450819D03*
X291689Y453912D03*
Y456912D03*
Y459912D03*
X313977Y33400D03*
X303575Y54516D03*
X316066Y108407D03*
X315100Y116400D03*
X307400Y122300D03*
X304436Y135897D03*
X307500Y125635D03*
X315900Y125900D03*
X313800Y124300D03*
X307560Y128500D03*
X305936Y143897D03*
X309936D03*
X313936D03*
X309521Y226397D03*
X307487Y219503D03*
X304987D03*
X310449Y218617D03*
X317110Y219140D03*
X309521Y229786D03*
Y235352D03*
Y238741D03*
X307500Y256500D03*
X305000Y252400D03*
X307600Y252300D03*
X307800Y259200D03*
X312114Y288439D03*
X312272Y282107D03*
X302800Y286200D03*
X311670Y285160D03*
X302879Y282487D03*
Y279686D03*
X309700Y294789D03*
X315810Y293450D03*
X312315Y293207D03*
X317430Y295665D03*
X314820Y296128D03*
X314201Y302361D03*
X314180Y299440D03*
X303077Y297519D03*
X314132Y310178D03*
X314170Y307020D03*
X309500Y315000D03*
X304000Y305000D03*
X303000Y309200D03*
X306200Y308800D03*
X311000Y320500D03*
X312300Y340700D03*
X315075Y366500D03*
X314340Y373296D03*
X311925Y366475D03*
X312226Y382766D03*
X308500Y382100D03*
X314985Y397639D03*
Y394639D03*
X308926Y401900D03*
X314969Y456527D03*
X322218Y3000D03*
X319175Y60200D03*
X321800Y60055D03*
X322600Y76100D03*
X322500Y102900D03*
X331881Y108593D03*
Y104577D03*
X320500Y100400D03*
X331881Y112608D03*
X324011Y118843D03*
X324023Y121943D03*
Y115643D03*
X320765Y114582D03*
X320938Y122677D03*
X318000Y117200D03*
X329297Y134594D03*
Y129890D03*
X321276Y134532D03*
X321349Y130044D03*
X320239Y151075D03*
X317936Y143897D03*
X323509Y153377D03*
X329005Y152657D03*
X321600Y142100D03*
X323384Y157378D03*
X331405Y157411D03*
X323384Y165378D03*
Y161378D03*
X331405Y164911D03*
Y159911D03*
Y154911D03*
Y167411D03*
X323384Y169378D03*
Y173378D03*
Y177378D03*
X331405Y177411D03*
Y179911D03*
Y174911D03*
Y169911D03*
Y182926D03*
Y172411D03*
Y187411D03*
Y192411D03*
Y189911D03*
X320054Y195163D03*
X319601Y201140D03*
X326932Y205685D03*
X326733Y209885D03*
X321045Y210257D03*
X320937Y212839D03*
X326733Y201485D03*
X320054Y198663D03*
X326323Y226349D03*
X317922Y226373D03*
X326731Y213648D03*
X320931Y215387D03*
X326323Y229738D03*
X317922Y229762D03*
Y238717D03*
Y235328D03*
X326323Y235304D03*
Y238693D03*
X327162Y278972D03*
X317670Y291430D03*
X330900Y314700D03*
X325038Y356890D03*
X329925Y356016D03*
X325900Y365643D03*
X326100Y375717D03*
X326200Y370681D03*
X325320Y390118D03*
X325200Y383900D03*
X331500Y383300D03*
X326375Y380724D03*
X332470Y397092D03*
Y394092D03*
X331646Y466536D03*
X342218Y3000D03*
X337375Y76600D03*
X342900Y66100D03*
X339900Y66000D03*
X339908Y104577D03*
Y108593D03*
X342200Y100500D03*
X342180Y106900D03*
X339101Y117328D03*
Y121128D03*
X339908Y112609D03*
X337842Y128533D03*
X333278Y151129D03*
X339369Y151952D03*
X339800Y154911D03*
Y159911D03*
Y165911D03*
X339939Y162911D03*
X339800Y169911D03*
Y176911D03*
Y179911D03*
X339812Y173380D03*
X339800Y182926D03*
Y185911D03*
Y189911D03*
X337083Y197000D03*
X337400Y193449D03*
X337004Y202113D03*
Y206113D03*
Y210113D03*
X334723Y226349D03*
Y229738D03*
X334724Y238669D03*
Y235280D03*
X337467Y236984D03*
X336312Y286352D03*
X336461Y283202D03*
X340612Y278972D03*
X339700Y295900D03*
X347100Y313700D03*
X342604Y318773D03*
X345500Y342690D03*
X335475Y358500D03*
X335700Y376400D03*
X335500Y363200D03*
X335475Y367500D03*
X335708Y372008D03*
X334600Y383300D03*
X335500Y380000D03*
X334112Y447668D03*
X351331Y20788D03*
Y40788D03*
Y60788D03*
Y80788D03*
Y100788D03*
Y120788D03*
Y140788D03*
Y160788D03*
Y180788D03*
Y200788D03*
Y220788D03*
Y240788D03*
Y260788D03*
Y280788D03*
Y300788D03*
X349290Y337646D03*
X351331Y357531D03*
Y377531D03*
Y397531D03*
Y417531D03*
Y437531D03*
X375904Y-438145D03*
X375964Y-215959D03*
X375876Y-159873D03*
X375964Y12313D03*
X375904Y68399D03*
X375964Y381585D03*
X379304Y-438145D03*
X379364Y-215959D03*
X379276Y-159873D03*
X379364Y12313D03*
X379304Y68399D03*
X379364Y381585D03*
X396992Y-464207D03*
X400392D03*
X397080Y-121021D03*
X400480D03*
G54D22*
X23819Y339154D03*
Y349154D03*
Y359154D03*
Y369154D03*
Y379154D03*
Y389154D03*
Y399154D03*
Y409154D03*
X65709Y52244D03*
X75709Y42244D03*
Y52244D03*
X95709Y42244D03*
X85709D03*
X95709Y52244D03*
X85709D03*
G54D23*
X63898Y24764D03*
X73898D03*
X90472D03*
X100472D03*
X117047D03*
X127047D03*
X211142D03*
X221142D03*
X237717D03*
X247717D03*
G54D26*
X62458Y346425D03*
Y343275D03*
Y355873D03*
X58564Y354280D03*
X65607Y352724D03*
Y359023D03*
Y371584D03*
X62458Y390481D03*
X75056Y346425D03*
X68757D03*
X81355D03*
X78206Y349574D03*
X68757Y352724D03*
X71906Y355873D03*
X75056Y359023D03*
X65607Y349574D03*
X71906D03*
X68757D03*
X78206Y359023D03*
X75056Y352724D03*
Y349574D03*
X78206Y355873D03*
X65607D03*
X68757Y362173D03*
Y359023D03*
X71906D03*
X75056Y355873D03*
X71906Y352724D03*
X68757Y355873D03*
X78206Y374733D03*
Y362173D03*
X75056D03*
X71906Y371584D03*
X75056Y365322D03*
X71906D03*
X68757D03*
Y371584D03*
X75056Y374733D03*
X71906D03*
X68757D03*
X65607D03*
X71906Y362173D03*
X78206Y365322D03*
Y371584D03*
X75056Y377883D03*
X68757Y384182D03*
X65607Y387332D03*
X75018Y381033D03*
X68757Y377883D03*
X78206Y381033D03*
X65607D03*
X71906Y377883D03*
X65607Y384182D03*
X68719Y381033D03*
X78206Y377883D03*
X71906Y387332D03*
X71869Y381033D03*
X71906Y384182D03*
X87617Y352724D03*
X90766Y349574D03*
X93916Y352724D03*
X81355Y355873D03*
X90766Y352724D03*
X87617Y349574D03*
X90766Y355873D03*
X87617D03*
X90766Y359023D03*
X81355Y349574D03*
X87617Y359023D03*
Y365322D03*
Y371584D03*
X81355Y365322D03*
Y371584D03*
X90766Y374733D03*
Y362173D03*
X81355D03*
X87617D03*
X81355Y374733D03*
X87617D03*
X90766Y371584D03*
Y365322D03*
X81355Y377883D03*
Y387332D03*
Y384182D03*
X87617D03*
X90766Y377883D03*
X87617Y390481D03*
X81355Y381033D03*
X87617Y387332D03*
X90766Y381033D03*
X87617Y377883D03*
X90766Y390481D03*
Y387332D03*
Y384182D03*
X92360Y394175D03*
X89210D03*
X103365Y346425D03*
X106564Y346400D03*
X100253Y346387D03*
X100215Y352724D03*
X103383Y349556D03*
X93916Y359023D03*
X97066Y355873D03*
X93916Y349574D03*
X97066D03*
X106515Y352724D03*
X106514Y349574D03*
X97066Y352724D03*
X100215Y355873D03*
X93916D03*
X100215Y349574D03*
X103383Y387350D03*
X100215Y384182D03*
X93916Y377883D03*
X97066Y381033D03*
X100215Y387332D03*
X97066D03*
X93916Y384182D03*
X97066D03*
X100215Y381033D03*
X93916D03*
Y387332D03*
X166300Y212300D03*
X175359Y153286D03*
X181495Y153449D03*
X175196Y159748D03*
X178346Y162898D03*
Y156599D03*
X181495Y159748D03*
X175196Y156599D03*
X181495D03*
Y166047D03*
X184645D03*
X181495Y162898D03*
X178346Y159748D03*
Y172347D03*
X181495Y178646D03*
Y175496D03*
X184645Y181795D03*
X181495D03*
Y172347D03*
X184645Y175496D03*
X174569Y180202D03*
X178346Y175496D03*
X175196Y172347D03*
X173000Y170200D03*
X181495Y169197D03*
X178346Y184945D03*
X181495D03*
Y197506D03*
X178346D03*
Y191244D03*
X181495D03*
X175196Y197506D03*
X174336Y192800D03*
X181495Y188095D03*
X178346D03*
X175196Y200655D03*
X178346D03*
Y210104D03*
X181495Y203805D03*
Y206955D03*
X175196Y210104D03*
X178346Y206955D03*
X175196D03*
Y203805D03*
X178346D03*
X171836Y200655D03*
Y198300D03*
X181495Y200655D03*
X178346Y213254D03*
Y225852D03*
X181495Y219553D03*
X175196Y213254D03*
X184645Y219553D03*
X178346Y229002D03*
X181495Y225852D03*
Y222703D03*
X184645Y229002D03*
X174600Y217800D03*
X181495Y216403D03*
X174079Y234604D03*
X175196Y229002D03*
X181495D03*
X187794Y153449D03*
X192400Y152804D03*
X184645Y153449D03*
X197243Y156599D03*
X187794Y159748D03*
X197243Y166047D03*
X194094Y162898D03*
X197243Y159748D03*
X194094D03*
X197243Y162898D03*
X184645Y156599D03*
X187794Y162898D03*
Y166047D03*
X184645Y162898D03*
Y159748D03*
X190944Y162898D03*
Y159748D03*
X194094Y166047D03*
X190944D03*
X200393Y162898D03*
X187794Y156599D03*
Y178646D03*
X197243D03*
X187794Y181795D03*
X194094Y169197D03*
X190944Y172347D03*
Y175496D03*
X197243D03*
X190944Y178646D03*
Y181795D03*
X187794Y175496D03*
X184645Y178646D03*
X190944Y169197D03*
X187794Y172347D03*
X184645Y169197D03*
Y172347D03*
X187794Y169197D03*
X197243Y191244D03*
Y197506D03*
Y184945D03*
X190944Y197506D03*
Y184945D03*
Y188095D03*
Y191244D03*
X187794Y197506D03*
Y184945D03*
X184645Y197506D03*
Y184945D03*
Y191244D03*
Y188095D03*
X197243Y203805D03*
X184645Y206955D03*
X197243Y200655D03*
X190944D03*
Y210104D03*
Y203805D03*
X187794Y200655D03*
X184645Y210104D03*
Y200655D03*
Y203805D03*
X187794Y210104D03*
X190944Y219553D03*
X194094Y222703D03*
X200393Y229002D03*
X194094Y225852D03*
X187794D03*
Y219553D03*
X197243D03*
X187794Y213254D03*
X190944D03*
Y222702D03*
X200393Y222703D03*
X197243Y225852D03*
Y222703D03*
X184645Y225852D03*
X187794Y222703D03*
X184645D03*
Y213254D03*
X194094Y219553D03*
Y232151D03*
X184645D03*
X187794Y229002D03*
X197243Y235301D03*
X194094Y229002D03*
X197243D03*
Y232151D03*
X209842Y153449D03*
Y159748D03*
X206692Y156599D03*
X209842D03*
X203542Y166047D03*
X206692Y162898D03*
X203542D03*
X200393Y159748D03*
X209842Y166047D03*
Y162898D03*
X212991D03*
X203542Y159748D03*
X200393Y166047D03*
X206692D03*
X212991D03*
X206692Y159748D03*
X209842Y169197D03*
X203542D03*
X212991D03*
X206692D03*
X212991Y181795D03*
X206692Y178646D03*
X209842Y181795D03*
X200393Y169197D03*
X206692Y181795D03*
X203542Y175496D03*
X206692D03*
X209842D03*
X200393D03*
X203542Y191244D03*
X206692D03*
X209842Y184945D03*
X200393Y191244D03*
X203542Y197506D03*
X209842D03*
X212991Y184945D03*
Y197506D03*
X203542Y210104D03*
X212991Y206955D03*
Y210104D03*
X209842D03*
X200393D03*
X203542Y200655D03*
X209842D03*
X203542Y206955D03*
X212991Y203805D03*
X206692Y206955D03*
X209842D03*
X200393D03*
X212991Y200655D03*
Y219553D03*
X200393Y213254D03*
Y219553D03*
X212991Y222740D03*
X209842Y213254D03*
Y225852D03*
X203542Y222703D03*
X200393Y225852D03*
X206692Y219553D03*
X203542Y225852D03*
X206692Y229002D03*
X212991D03*
X203542Y219553D03*
X206692Y222703D03*
X209842D03*
X212991Y225890D03*
X206692Y225852D03*
X203542Y229002D03*
Y232151D03*
X209746Y235397D03*
X203542Y235301D03*
X209842Y232151D03*
X200393D03*
X206692D03*
X212991D03*
X209842Y229002D03*
X225658Y153369D03*
X225552Y156599D03*
Y159748D03*
X222402Y162898D03*
X219253Y166047D03*
X225552Y162898D03*
Y166047D03*
X222402D03*
X219253Y159748D03*
X222402D03*
X219253Y162898D03*
Y156599D03*
X222402D03*
X217697Y174852D03*
X219253Y178646D03*
X225552D03*
X222402Y169197D03*
X225552Y181795D03*
X214547Y174852D03*
X225552Y169197D03*
X219253D03*
X219290Y191207D03*
X225552Y184945D03*
Y197543D03*
Y191244D03*
Y188095D03*
X222402Y206955D03*
Y213254D03*
X228739Y222703D03*
X216141D03*
X228702Y229002D03*
X225590Y222720D03*
X216103Y219591D03*
X219253Y219553D03*
X225590Y225852D03*
X222440Y222703D03*
X225552Y219553D03*
X222402D03*
Y229002D03*
X222440Y225852D03*
X219290D03*
Y222703D03*
X219253Y232151D03*
X225552Y229002D03*
X219253D03*
X235001Y153449D03*
X228702Y162898D03*
X238150D03*
X235001Y166047D03*
X231851D03*
X238150D03*
X228702Y159748D03*
Y166047D03*
X238150Y156599D03*
X235001D03*
X231851D03*
Y162898D03*
Y159748D03*
X235001Y162898D03*
Y159748D03*
X238150D03*
X241300D03*
X228702Y169197D03*
X238150D03*
X231851D03*
Y178646D03*
X235001Y169197D03*
X241300Y175496D03*
Y178646D03*
Y172347D03*
X228702Y181795D03*
Y178646D03*
X231851Y191244D03*
X241300D03*
X235001Y184945D03*
X228702Y191244D03*
X235001Y188095D03*
Y191244D03*
Y197506D03*
X241300Y184945D03*
Y197506D03*
Y188095D03*
X235001Y200655D03*
Y206955D03*
X244450Y200655D03*
X228702D03*
X235001Y203805D03*
X231851D03*
X228702D03*
X241300Y200655D03*
X235001Y210104D03*
X231851D03*
X228702D03*
X235001Y219553D03*
X241300Y213254D03*
X238150Y219553D03*
X238188Y225852D03*
X228702Y219553D03*
X228739Y213254D03*
X235038Y225890D03*
X228739Y225852D03*
X238150Y222703D03*
X231889Y219591D03*
Y222740D03*
X235038D03*
X231889Y225890D03*
X228739Y216441D03*
X241338Y225890D03*
X238630Y235654D03*
X231851Y232151D03*
X241300D03*
X231851Y229002D03*
X241300D03*
X239870Y237596D03*
X242870D03*
X235038Y229039D03*
X255492Y152905D03*
X244450Y156599D03*
X250749Y159748D03*
X244450D03*
X250749Y169197D03*
X247637Y162898D03*
X247599Y166047D03*
X253898Y172347D03*
Y178646D03*
X247599Y181795D03*
Y175496D03*
X253898Y169197D03*
X257048Y172347D03*
X250749Y181795D03*
X244450D03*
X250749Y175496D03*
Y178646D03*
X247599Y172347D03*
X244450Y175496D03*
X250749Y172347D03*
X247599Y178646D03*
X253898Y175496D03*
X244450Y178646D03*
Y172347D03*
X250749Y184945D03*
X244450Y169197D03*
X253898Y191244D03*
Y184945D03*
X247599Y197506D03*
Y188095D03*
X244450Y197506D03*
X247599Y191244D03*
X257048Y197506D03*
X253898D03*
X250749D03*
X247599Y184945D03*
X244450Y188095D03*
X257048Y191244D03*
X250749Y188095D03*
X244450Y184945D03*
X250749Y191244D03*
X244450D03*
X247599Y203805D03*
X253898Y206955D03*
Y200655D03*
X250749Y203805D03*
X247599Y206955D03*
Y210104D03*
X250749Y206955D03*
X247599Y200655D03*
X257048Y206955D03*
X250749Y200655D03*
X257048D03*
X250749Y210104D03*
X244450Y203805D03*
X250749Y222703D03*
Y225852D03*
X253898Y219553D03*
Y222703D03*
X257048Y225890D03*
Y219553D03*
X250749D03*
X257048Y213254D03*
X250749D03*
X247599D03*
X253898D03*
X247637Y225852D03*
X250749Y232151D03*
X257048Y235301D03*
X244020Y235518D03*
X244487Y229002D03*
X244450Y232151D03*
X247599D03*
X253898D03*
X257048D03*
X250749Y229002D03*
X253898D03*
X250749Y235301D03*
X253898D03*
X268510Y179088D03*
X262880Y178977D03*
X267722Y176791D03*
X264222D03*
X271209Y177524D03*
X270472Y188488D03*
X264118Y188095D03*
X268391Y207262D03*
X260269Y207358D03*
X266080Y207262D03*
X262580D03*
X269391Y214593D03*
X261269Y214657D03*
X263580Y214593D03*
X267080D03*
X285980Y163487D03*
X285482Y168102D03*
X286105Y172936D03*
Y182385D03*
X273644Y174267D03*
X282975Y172975D03*
X286105Y176085D03*
X285482Y190187D03*
X286105Y197989D03*
X289254Y194839D03*
X286105Y185534D03*
Y194839D03*
Y201139D03*
Y204288D03*
Y213721D03*
X289110Y163487D03*
X292260D03*
X295410Y169786D03*
X292404Y176085D03*
X295410Y172936D03*
X289254Y172792D03*
X292260Y169643D03*
X295410Y179235D03*
X292384Y172936D03*
X289254Y176085D03*
Y182385D03*
X292260Y179235D03*
X289111D03*
X297372Y196616D03*
X292361Y197970D03*
X292404Y191690D03*
X289254D03*
X292404Y185534D03*
Y194983D03*
X295410Y194839D03*
X295411Y185534D03*
X289254D03*
Y197989D03*
X289091Y204331D03*
X289254Y210587D03*
X298714Y210477D03*
X292404Y210587D03*
Y201282D03*
X299667Y201334D03*
X292404Y213737D03*
X289254Y201139D03*
X295410Y210587D03*
X289254Y213737D03*
X308008Y163487D03*
X311158D03*
X308008Y166637D03*
X314307Y163487D03*
X311301Y182385D03*
X314930Y171289D03*
Y177588D03*
X305002Y176085D03*
Y169786D03*
Y172936D03*
X308152Y169786D03*
X311158Y169643D03*
X308152Y172936D03*
Y176085D03*
Y182385D03*
X305002Y179235D03*
X308152D03*
X314930Y180738D03*
Y174439D03*
X311158Y185534D03*
X314307Y191690D03*
X311158Y194839D03*
X308008Y191690D03*
X311158D03*
X308008Y188540D03*
Y185391D03*
Y198133D03*
X314307Y185534D03*
X311158Y188540D03*
X308008Y194839D03*
X311158Y197989D03*
X314307Y194839D03*
Y197989D03*
X311158Y204288D03*
X314307Y207438D03*
X303940Y212664D03*
X311158Y201139D03*
X308008Y207438D03*
X308152Y204432D03*
X305002D03*
X311158Y210587D03*
X308008Y210731D03*
X305002Y210587D03*
X314307Y201139D03*
Y204288D03*
Y210587D03*
X308460Y214178D03*
X311158Y213737D03*
X314307D03*
G54D35*
X372604Y-455313D03*
Y-430313D03*
X372664Y-223791D03*
Y-198791D03*
X372576Y-177041D03*
Y-152041D03*
X372664Y4481D03*
Y29481D03*
X372604Y51231D03*
Y76231D03*
X372664Y373753D03*
Y398753D03*
X393692Y-481375D03*
X382604Y-455313D03*
X393692Y-456375D03*
X382604Y-430313D03*
X382664Y-223791D03*
Y-198791D03*
X382576Y-177041D03*
Y-152041D03*
X393780Y-128853D03*
Y-103853D03*
X393750Y-82222D03*
Y-57222D03*
X382664Y4481D03*
Y29481D03*
X382604Y51231D03*
Y76231D03*
X393750Y200538D03*
Y225538D03*
Y247050D03*
Y272050D03*
X382664Y373753D03*
X393750Y398810D03*
X382664Y398753D03*
X393750Y423810D03*
X403692Y-481375D03*
Y-456375D03*
X403780Y-128853D03*
Y-103853D03*
X403750Y-82222D03*
D03*
Y-57222D03*
D03*
Y200538D03*
D03*
Y225538D03*
D03*
Y247050D03*
D03*
Y272050D03*
D03*
Y398810D03*
D03*
Y423810D03*
D03*
X413750Y-82222D03*
Y-57222D03*
Y200538D03*
Y225538D03*
Y247050D03*
Y272050D03*
Y398810D03*
Y423810D03*
G54D21*
X23736Y127758D03*
Y130758D03*
X32236Y127758D03*
Y130758D03*
X40736Y127758D03*
Y130758D03*
X49236Y127758D03*
Y130758D03*
X39493Y222932D03*
X41993D03*
X44149Y227332D03*
X39493Y220332D03*
X41993D03*
X44149Y224732D03*
X52237Y129522D03*
X373480Y-210223D03*
X370965D03*
Y-206970D03*
X376406Y-206985D03*
X373480Y-206970D03*
X372271Y-213263D03*
X373480Y18049D03*
X370965D03*
X372271Y15009D03*
X370965Y21302D03*
X376406Y21287D03*
X373480Y21302D03*
X372271Y384281D03*
X376406Y390559D03*
X373480Y387321D03*
Y390574D03*
X370965Y387321D03*
Y390574D03*
X383057Y-213263D03*
X381848Y-206970D03*
X384363D03*
Y-210223D03*
X381848D03*
X378922Y-206970D03*
X392081Y-115285D03*
Y-112032D03*
X383057Y15009D03*
X384363Y18049D03*
X381848D03*
Y21302D03*
X384363D03*
X378922D03*
X391950Y214106D03*
Y217359D03*
X378922Y390574D03*
X381848D03*
Y387321D03*
X384363Y390574D03*
Y387321D03*
X383057Y384281D03*
X391950Y412378D03*
Y415631D03*
X394596Y-115285D03*
X393387Y-118325D03*
X404173D03*
X405479Y-115285D03*
X402964D03*
X397522Y-112047D03*
X394596Y-112032D03*
X402964D03*
X405479D03*
X400038D03*
X393357Y211066D03*
X403857D03*
X394450Y217359D03*
Y214106D03*
X396950Y217359D03*
X399450Y217344D03*
X402450Y217359D03*
X404950D03*
X402450Y214106D03*
X404950D03*
X394450Y415631D03*
Y412378D03*
X396950Y415631D03*
X399450Y415616D03*
X393357Y409338D03*
X402450Y415631D03*
X404950D03*
X402450Y412378D03*
X404950D03*
X403857Y409338D03*
X414143Y211066D03*
X415550Y214106D03*
Y217359D03*
X413050D03*
Y214106D03*
X410550Y217359D03*
X408050Y217344D03*
X415550Y412378D03*
Y415631D03*
X413050D03*
Y412378D03*
X410550Y415631D03*
X408050Y415616D03*
X414143Y409338D03*
G54D32*
X143945Y354146D03*
X212991Y213254D03*
X222402Y178646D03*
X219253Y197506D03*
X222402D03*
X219253Y188095D03*
Y200655D03*
Y206955D03*
Y210104D03*
Y203805D03*
Y213254D03*
X287761Y366200D03*
X287500Y376900D03*
X295500Y354920D03*
G54D37*
X441000Y-454000D03*
X451000D03*
X441000Y-333400D03*
X451000D03*
X441000Y2000D03*
X451000D03*
X441000Y116000D03*
X451000D03*
G54D15*
X17716Y18465D03*
X45276D03*
X264173Y20040D03*
X291733D03*
X309055Y18465D03*
X336615D03*
G54D30*
X153237Y58583D03*
X165048Y52677D03*
X155205D03*
X161111Y58583D03*
X168985D03*
X182764Y52677D03*
X172922D03*
X176859Y58583D03*
X184733D03*
G54D36*
X441000Y-444000D03*
X451000D03*
Y-355000D03*
X441000D03*
Y-323400D03*
X451000D03*
Y-245000D03*
X441000D03*
X451000Y-215000D03*
X441000D03*
Y-136600D03*
X451000D03*
Y-107000D03*
X441000D03*
Y-18000D03*
X451000D03*
X441000Y12000D03*
X451000D03*
Y96000D03*
X441000D03*
Y126000D03*
X451000D03*
Y200000D03*
X441000D03*
X451000Y230000D03*
X441000D03*
Y304000D03*
X451000D03*
Y336000D03*
X441000D03*
Y420000D03*
X451000D03*
G54D40*
X441000Y-126600D03*
X451000D03*
X441000Y-8000D03*
X451000D03*
X441000Y314000D03*
X451000D03*
X441000Y430000D03*
X451000D03*
G54D11*
X-61709Y56192D03*
X-51709D03*
X-61100Y250316D03*
X-61000Y382816D03*
X-51100Y250316D03*
X-51000Y382816D03*
X-35000Y56184D03*
X-25000D03*
X-25100Y250316D03*
X-35100D03*
X-36000Y418816D03*
X-26000D03*
G54D25*
X65945Y297776D03*
G54D31*
X144685D03*
G54D24*
X65709Y42244D03*
G54D10*
X-56709Y43008D03*
X-30000Y43000D03*
G54D29*
X143118Y44803D03*
X194851D03*
G54D27*
X105315Y186571D03*
G54D28*
X105316Y213343D03*
G54D17*
X24016Y89331D03*
X330315D03*
G54D33*
X236220Y424016D03*
X301181D03*
G54D16*
X22047Y46417D03*
X333466D03*
G54D20*
X27300Y68200D03*
X340639Y432809D03*
G54D19*
X15922Y224568D03*
Y227168D03*
X18422Y224568D03*
Y227168D03*
X21000Y227000D03*
Y224500D03*
X47440Y304225D03*
Y301336D03*
X68990Y257000D03*
X90800Y258225D03*
X100360Y116500D03*
X97177Y263320D03*
X141520Y399700D03*
X149600Y410500D03*
X154050Y137100D03*
X155325Y139440D03*
X331741Y125796D03*
X325007Y328608D03*
Y326008D03*
X327704Y328635D03*
Y326035D03*
X325007Y323508D03*
X327704Y323535D03*
X373420Y-447134D03*
X370905D03*
Y-443881D03*
X373420D03*
X376346Y-447134D03*
X372211Y-440841D03*
X372183Y-162569D03*
X373392Y-168862D03*
X370877D03*
Y-165609D03*
X373392D03*
X376318Y-168862D03*
X373420Y59410D03*
X370905D03*
Y62663D03*
X373420D03*
X376346Y59410D03*
X372211Y65703D03*
X391993Y-473196D03*
Y-469943D03*
X381788Y-443881D03*
X384303D03*
Y-447134D03*
X378862Y-447119D03*
X381788Y-447134D03*
X382997Y-440841D03*
X381760Y-165609D03*
X384275D03*
Y-168862D03*
X378834Y-168847D03*
X381760Y-168862D03*
X382969Y-162569D03*
X391950Y-74043D03*
Y-70790D03*
X381788Y62663D03*
X384303D03*
Y59410D03*
X378862Y59425D03*
X381788Y59410D03*
X382997Y65703D03*
X391950Y255229D03*
Y258482D03*
X405391Y-473196D03*
X399950Y-473181D03*
X402876Y-473196D03*
X394508D03*
X397434D03*
X402876Y-469943D03*
X405391D03*
X404085Y-466903D03*
X393299D03*
X394508Y-469943D03*
X399450Y-74028D03*
X394450Y-74043D03*
Y-70790D03*
X396950Y-74043D03*
X405050D03*
X402550D03*
X405050Y-70790D03*
X402550D03*
X393357Y-67750D03*
X403643D03*
X394450Y255229D03*
X396950D03*
X399450Y255244D03*
X405050Y255229D03*
X402550D03*
X394450Y258482D03*
X393357Y261522D03*
X405050Y258482D03*
X402550D03*
X403643Y261522D03*
X415550Y-70790D03*
Y-74043D03*
X413050D03*
Y-70790D03*
X410550Y-74043D03*
X408050Y-74028D03*
X414143Y-67750D03*
X415550Y255229D03*
X413050D03*
X410550D03*
X408050Y255244D03*
X415550Y258482D03*
X413050D03*
X414143Y261522D03*
G54D34*
X314930Y168140D03*
G54D18*
X19200Y102700D03*
X45500Y41500D03*
X35304Y58317D03*
X51500Y258200D03*
X58976Y36402D03*
X52050Y208760D03*
X56600Y320500D03*
X52900Y360000D03*
X52600Y376600D03*
X67330Y169267D03*
X75300Y183875D03*
X75000Y214000D03*
X70900Y241500D03*
X77900Y274700D03*
X70000Y280000D03*
X72700Y301200D03*
X71000Y394400D03*
X88000Y66500D03*
X90500Y397600D03*
X82500D03*
X119000Y44600D03*
X118500Y75500D03*
X116500Y74000D03*
X113000Y158000D03*
X122156Y157844D03*
X122876Y242800D03*
X121175Y385125D03*
X119200Y406175D03*
X126425Y57000D03*
X126500Y158000D03*
X138100Y213600D03*
X133000Y361500D03*
X151900Y213200D03*
X148316Y359086D03*
X159000Y135000D03*
X153744Y217435D03*
X153800Y214900D03*
X161300Y354600D03*
X180600Y360200D03*
X196050Y358770D03*
X204258Y286691D03*
X198672Y318175D03*
X218600Y92100D03*
X221300D03*
X219900Y101300D03*
X222402Y191244D03*
X227841Y275773D03*
X219339Y284138D03*
X219359Y281580D03*
X223646Y293960D03*
X225867Y345033D03*
X224632Y369825D03*
X225700Y362500D03*
X220515Y384900D03*
X234537Y74638D03*
X235001Y178646D03*
Y175496D03*
X241300Y210104D03*
X240500Y316575D03*
X239750Y394970D03*
X252925Y54000D03*
X246200Y74600D03*
X255000Y82700D03*
X243750Y369730D03*
X268442Y153299D03*
X265942D03*
Y150799D03*
X268442D03*
X267100Y265000D03*
X269016Y266991D03*
X266250Y297900D03*
X271100Y346575D03*
X265320Y392290D03*
X277000Y51665D03*
X274500Y58000D03*
X286106Y210587D03*
X275700Y403500D03*
X300425Y54516D03*
X290000Y67975D03*
X300070Y84000D03*
X295729Y453912D03*
Y456912D03*
Y459912D03*
X297738Y452418D03*
Y458418D03*
Y455418D03*
X316025Y60200D03*
X309570Y84000D03*
X306500Y301500D03*
X308906Y362637D03*
X331741Y138243D03*
X328087Y141608D03*
X331641Y141743D03*
X325593Y406500D03*
X329093D03*
X318593D03*
X322093D03*
X339900Y69100D03*
X339700Y293000D03*
X374975Y-435380D03*
X374666Y-218571D03*
X374947Y-157108D03*
X374666Y9701D03*
X374975Y71164D03*
X374666Y378973D03*
X380602Y-435533D03*
X380293Y-218724D03*
X380574Y-157261D03*
X380293Y9548D03*
X380602Y71011D03*
X380293Y378820D03*
X396063Y-461442D03*
X401690Y-461595D03*
X401409Y-123786D03*
X395782Y-123633D03*
G54D38*
X451000Y-345000D03*
X441000D03*
X451000Y-235000D03*
X441000D03*
X451000Y106000D03*
X441000D03*
X451000Y210000D03*
X441000D03*
G54D39*
X451000Y-225000D03*
X441000D03*
X451000Y-117000D03*
X441000D03*
X451000Y220000D03*
X441000D03*
X451000Y326000D03*
X441000D03*
G54D13*
X-30100Y263500D03*
G54D12*
X-56100D03*
X-56000Y396000D03*
X-31000Y432000D03*
%LPC*%
G75*
G54D41*
G01X2010999Y-388000D02*
Y1475775D01*
X-407000D01*
Y-386798D01*
Y-755294D01*
Y-793716D01*
X-368578D01*
X1942346D01*
X2010999D01*
Y-725063D01*
Y-388000D01*
G01X-53307Y-609436D02*
Y-684436D01*
X446693D01*
Y-609436D01*
X-53307D01*
G01X-41307Y-674436D02*
Y-679436D01*
G01X-42764Y-674436D02*
X-39850D01*
G01X-34940Y-679436D02*
X-37474D01*
Y-674436D01*
X-34940D01*
G01X-35954Y-676853D02*
X-37474D01*
G01X-32374Y-674436D02*
Y-679436D01*
X-29840D01*
G01X-26007Y-679603D02*
X-26134Y-679519D01*
Y-679353D01*
X-26007Y-679269D01*
X-25880Y-679353D01*
Y-679519D01*
X-26007Y-679603D01*
G01Y-677353D02*
X-26134Y-677269D01*
Y-677103D01*
X-26007Y-677019D01*
X-25880Y-677103D01*
Y-677269D01*
X-26007Y-677353D01*
G01X-21224Y-681103D02*
X-21857Y-680269D01*
X-22174Y-679436D01*
Y-676103D01*
X-21857Y-675269D01*
X-21224Y-674436D01*
G01X-15807D02*
X-16314Y-674603D01*
X-16694Y-675019D01*
X-16947Y-675519D01*
X-17137Y-676186D01*
X-17200Y-676936D01*
X-17137Y-677686D01*
X-16947Y-678353D01*
X-16694Y-678853D01*
X-16314Y-679269D01*
X-15807Y-679436D01*
X-15300Y-679269D01*
X-14920Y-678853D01*
X-14667Y-678353D01*
X-14477Y-677686D01*
X-14414Y-676936D01*
X-14477Y-676186D01*
X-14667Y-675519D01*
X-14920Y-675019D01*
X-15300Y-674603D01*
X-15807Y-674436D01*
G01X-12100Y-678436D02*
X-11720Y-679019D01*
X-11214Y-679353D01*
X-10644Y-679436D01*
X-10137Y-679353D01*
X-9630Y-678936D01*
X-9314Y-678436D01*
X-9250Y-677936D01*
X-9377Y-677353D01*
X-9820Y-676936D01*
X-10264Y-676769D01*
X-10834D01*
G01X-10264D02*
X-9884Y-676519D01*
X-9567Y-676103D01*
X-9440Y-675603D01*
X-9567Y-675103D01*
X-9884Y-674686D01*
X-10454Y-674436D01*
X-11024Y-674519D01*
X-11594Y-674853D01*
G01X-5290Y-681103D02*
X-4657Y-680269D01*
X-4340Y-679436D01*
Y-676103D01*
X-4657Y-675269D01*
X-5290Y-674436D01*
G01X-1900Y-678436D02*
X-1520Y-679019D01*
X-1014Y-679353D01*
X-444Y-679436D01*
X63Y-679353D01*
X570Y-678936D01*
X886Y-678436D01*
X950Y-677936D01*
X823Y-677353D01*
X380Y-676936D01*
X-64Y-676769D01*
X-634D01*
G01X-64D02*
X316Y-676519D01*
X633Y-676103D01*
X760Y-675603D01*
X633Y-675103D01*
X316Y-674686D01*
X-254Y-674436D01*
X-824Y-674519D01*
X-1394Y-674853D01*
G01X3390Y-675269D02*
X3770Y-674769D01*
X4213Y-674519D01*
X4720Y-674436D01*
X5353Y-674603D01*
X5796Y-675019D01*
X5923Y-675519D01*
X5860Y-676019D01*
X5606Y-676436D01*
X4340Y-677269D01*
X3770Y-677853D01*
X3390Y-678686D01*
X3263Y-679436D01*
X5923D01*
G01X9566D02*
X9693Y-678353D01*
X9883Y-677436D01*
X10136Y-676603D01*
X10453Y-675686D01*
X10960Y-674436D01*
X8426D01*
G01X13970Y-677769D02*
X15616D01*
G01X18690Y-675269D02*
X19070Y-674769D01*
X19513Y-674519D01*
X20020Y-674436D01*
X20653Y-674603D01*
X21096Y-675019D01*
X21223Y-675519D01*
X21160Y-676019D01*
X20906Y-676436D01*
X19640Y-677269D01*
X19070Y-677853D01*
X18690Y-678686D01*
X18563Y-679436D01*
X21223D01*
G01X23600Y-678436D02*
X23980Y-679019D01*
X24486Y-679353D01*
X25056Y-679436D01*
X25563Y-679353D01*
X26070Y-678936D01*
X26386Y-678436D01*
X26450Y-677936D01*
X26323Y-677353D01*
X25880Y-676936D01*
X25436Y-676769D01*
X24866D01*
G01X25436D02*
X25816Y-676519D01*
X26133Y-676103D01*
X26260Y-675603D01*
X26133Y-675103D01*
X25816Y-674686D01*
X25246Y-674436D01*
X24676Y-674519D01*
X24106Y-674853D01*
G01X30853Y-679436D02*
Y-674436D01*
X28510Y-678019D01*
X31676D01*
G01X33800Y-678686D02*
X34180Y-679103D01*
X34623Y-679353D01*
X35193Y-679436D01*
X35763Y-679269D01*
X36206Y-678936D01*
X36523Y-678353D01*
X36586Y-677686D01*
X36460Y-677019D01*
X36143Y-676603D01*
X35700Y-676269D01*
X35256Y-676186D01*
X34813Y-676269D01*
X34243Y-676603D01*
X34433Y-674436D01*
X36143D01*
G01X44190Y-679436D02*
Y-674436D01*
X46596D01*
G01X45710Y-676853D02*
X44190D01*
G01X48910Y-679436D02*
X50493Y-674436D01*
X52076Y-679436D01*
G01X51506Y-677686D02*
X49480D01*
G01X54263Y-679436D02*
X56923Y-674436D01*
G01X54263D02*
X56923Y-679436D01*
G01X60693Y-679603D02*
X60566Y-679519D01*
Y-679353D01*
X60693Y-679269D01*
X60820Y-679353D01*
Y-679519D01*
X60693Y-679603D01*
G01Y-677353D02*
X60566Y-677269D01*
Y-677103D01*
X60693Y-677019D01*
X60820Y-677103D01*
Y-677269D01*
X60693Y-677353D01*
G01X65476Y-681103D02*
X64843Y-680269D01*
X64526Y-679436D01*
Y-676103D01*
X64843Y-675269D01*
X65476Y-674436D01*
G01X70893D02*
X70386Y-674603D01*
X70006Y-675019D01*
X69753Y-675519D01*
X69563Y-676186D01*
X69500Y-676936D01*
X69563Y-677686D01*
X69753Y-678353D01*
X70006Y-678853D01*
X70386Y-679269D01*
X70893Y-679436D01*
X71400Y-679269D01*
X71780Y-678853D01*
X72033Y-678353D01*
X72223Y-677686D01*
X72286Y-676936D01*
X72223Y-676186D01*
X72033Y-675519D01*
X71780Y-675019D01*
X71400Y-674603D01*
X70893Y-674436D01*
G01X74600Y-678436D02*
X74980Y-679019D01*
X75486Y-679353D01*
X76056Y-679436D01*
X76563Y-679353D01*
X77070Y-678936D01*
X77386Y-678436D01*
X77450Y-677936D01*
X77323Y-677353D01*
X76880Y-676936D01*
X76436Y-676769D01*
X75866D01*
G01X76436D02*
X76816Y-676519D01*
X77133Y-676103D01*
X77260Y-675603D01*
X77133Y-675103D01*
X76816Y-674686D01*
X76246Y-674436D01*
X75676Y-674519D01*
X75106Y-674853D01*
G01X81410Y-681103D02*
X82043Y-680269D01*
X82360Y-679436D01*
Y-676103D01*
X82043Y-675269D01*
X81410Y-674436D01*
G01X84800Y-678436D02*
X85180Y-679019D01*
X85686Y-679353D01*
X86256Y-679436D01*
X86763Y-679353D01*
X87270Y-678936D01*
X87586Y-678436D01*
X87650Y-677936D01*
X87523Y-677353D01*
X87080Y-676936D01*
X86636Y-676769D01*
X86066D01*
G01X86636D02*
X87016Y-676519D01*
X87333Y-676103D01*
X87460Y-675603D01*
X87333Y-675103D01*
X87016Y-674686D01*
X86446Y-674436D01*
X85876Y-674519D01*
X85306Y-674853D01*
G01X90216Y-678853D02*
X90660Y-679269D01*
X91166Y-679436D01*
X91673Y-679269D01*
X92116Y-678769D01*
X92433Y-678019D01*
X92560Y-677269D01*
Y-676353D01*
X92433Y-675603D01*
X92116Y-674936D01*
X91736Y-674603D01*
X91293Y-674436D01*
X90786Y-674603D01*
X90406Y-674936D01*
X90153Y-675436D01*
X90026Y-676103D01*
X90153Y-676686D01*
X90470Y-677269D01*
X90850Y-677603D01*
X91293Y-677686D01*
X91800Y-677519D01*
X92180Y-677103D01*
X92560Y-676353D01*
G01X96266Y-679436D02*
X96393Y-678353D01*
X96583Y-677436D01*
X96836Y-676603D01*
X97153Y-675686D01*
X97660Y-674436D01*
X95126D01*
G01X100670Y-677769D02*
X102316D01*
G01X105200Y-678436D02*
X105580Y-679019D01*
X106086Y-679353D01*
X106656Y-679436D01*
X107163Y-679353D01*
X107670Y-678936D01*
X107986Y-678436D01*
X108050Y-677936D01*
X107923Y-677353D01*
X107480Y-676936D01*
X107036Y-676769D01*
X106466D01*
G01X107036D02*
X107416Y-676519D01*
X107733Y-676103D01*
X107860Y-675603D01*
X107733Y-675103D01*
X107416Y-674686D01*
X106846Y-674436D01*
X106276Y-674519D01*
X105706Y-674853D01*
G01X110490Y-677353D02*
X110933Y-676769D01*
X111313Y-676436D01*
X111820Y-676269D01*
X112263Y-676436D01*
X112580Y-676769D01*
X112833Y-677269D01*
X112896Y-677853D01*
X112833Y-678353D01*
X112580Y-678853D01*
X112200Y-679269D01*
X111756Y-679436D01*
X111250Y-679269D01*
X110806Y-678769D01*
X110553Y-678019D01*
X110490Y-677186D01*
X110616Y-676103D01*
X110806Y-675519D01*
X111123Y-674936D01*
X111566Y-674519D01*
X112010Y-674436D01*
X112453Y-674603D01*
X112770Y-675019D01*
G01X116793Y-679436D02*
Y-674436D01*
X116033Y-675436D01*
G01Y-679436D02*
X117553D01*
G01X122653D02*
Y-674436D01*
X120310Y-678019D01*
X123476D01*
G01X141693Y-609436D02*
Y-684436D01*
G01Y-659436D02*
X244693D01*
Y-634436D01*
G01X141693D02*
X244693D01*
G01X246693Y-609436D02*
Y-684436D01*
G01X244693Y-609436D02*
Y-684436D01*
G01X252200Y-669436D02*
Y-664436D01*
X253466D01*
X253973Y-664686D01*
X254353Y-665019D01*
X254670Y-665519D01*
X254923Y-666103D01*
X254986Y-666936D01*
X254923Y-667769D01*
X254670Y-668353D01*
X254353Y-668853D01*
X253973Y-669186D01*
X253466Y-669436D01*
X252200D01*
G01X257110D02*
X258693Y-664436D01*
X260276Y-669436D01*
G01X259706Y-667686D02*
X257680D01*
G01X263793Y-664436D02*
Y-669436D01*
G01X262336Y-664436D02*
X265250D01*
G01X270160Y-669436D02*
X267626D01*
Y-664436D01*
X270160D01*
G01X269146Y-666853D02*
X267626D01*
G01X273993Y-669603D02*
X273866Y-669519D01*
Y-669353D01*
X273993Y-669269D01*
X274120Y-669353D01*
Y-669519D01*
X273993Y-669603D01*
G01Y-667353D02*
X273866Y-667269D01*
Y-667103D01*
X273993Y-667019D01*
X274120Y-667103D01*
Y-667269D01*
X273993Y-667353D01*
G01X246693Y-659436D02*
X446693D01*
G01X252326Y-644436D02*
Y-639436D01*
X253846D01*
X254353Y-639686D01*
X254733Y-640269D01*
X254860Y-640936D01*
X254733Y-641603D01*
X254416Y-642103D01*
X253846Y-642353D01*
X252326D01*
G01X257553Y-644603D02*
X259833Y-639436D01*
G01X262336Y-644436D02*
Y-639436D01*
X265250Y-644436D01*
Y-639436D01*
G01X268893Y-644603D02*
X268766Y-644519D01*
Y-644353D01*
X268893Y-644269D01*
X269020Y-644353D01*
Y-644519D01*
X268893Y-644603D01*
G01Y-642353D02*
X268766Y-642269D01*
Y-642103D01*
X268893Y-642019D01*
X269020Y-642103D01*
Y-642269D01*
X268893Y-642353D01*
G01X246693Y-634436D02*
X446693D01*
G01X252326Y-619436D02*
Y-614436D01*
X253846D01*
X254353Y-614686D01*
X254733Y-615269D01*
X254860Y-615936D01*
X254733Y-616603D01*
X254416Y-617103D01*
X253846Y-617353D01*
X252326D01*
G01X257426Y-619436D02*
Y-614436D01*
X259010D01*
X259516Y-614686D01*
X259833Y-615019D01*
X259960Y-615686D01*
X259833Y-616353D01*
X259453Y-616769D01*
X259010Y-617019D01*
X257426D01*
G01X259010D02*
X259960Y-619436D01*
G01X263793D02*
X263286Y-619353D01*
X262843Y-619019D01*
X262463Y-618519D01*
X262210Y-617936D01*
X262083Y-617269D01*
Y-616603D01*
X262210Y-615936D01*
X262463Y-615353D01*
X262843Y-614853D01*
X263286Y-614519D01*
X263793Y-614436D01*
X264300Y-614519D01*
X264743Y-614853D01*
X265123Y-615353D01*
X265376Y-615936D01*
X265503Y-616603D01*
Y-617269D01*
X265376Y-617936D01*
X265123Y-618519D01*
X264743Y-619019D01*
X264300Y-619353D01*
X263793Y-619436D01*
G01X267626Y-618436D02*
X267943Y-618936D01*
X268323Y-619269D01*
X268766Y-619436D01*
X269273Y-619269D01*
X269653Y-618936D01*
X270033Y-618436D01*
X270160Y-617769D01*
Y-614436D01*
G01X275260Y-619436D02*
X272726D01*
Y-614436D01*
X275260D01*
G01X274246Y-616853D02*
X272726D01*
G01X280486Y-614853D02*
X280106Y-614603D01*
X279663Y-614436D01*
X279156D01*
X278586Y-614686D01*
X278143Y-615103D01*
X277826Y-615603D01*
X277573Y-616436D01*
X277510Y-617186D01*
X277636Y-617936D01*
X277826Y-618436D01*
X278206Y-618936D01*
X278650Y-619269D01*
X279093Y-619436D01*
X279536D01*
X279980Y-619269D01*
X280360Y-619019D01*
X280676Y-618686D01*
G01X284193Y-614436D02*
Y-619436D01*
G01X282736Y-614436D02*
X285650D01*
G01X289293Y-619603D02*
X289166Y-619519D01*
Y-619353D01*
X289293Y-619269D01*
X289420Y-619353D01*
Y-619519D01*
X289293Y-619603D01*
G01Y-617353D02*
X289166Y-617269D01*
Y-617103D01*
X289293Y-617019D01*
X289420Y-617103D01*
Y-617269D01*
X289293Y-617353D01*
G01X361693Y-659436D02*
Y-684436D01*
G01X364326Y-661936D02*
Y-666936D01*
X366860D01*
G01X369933Y-661936D02*
X371453D01*
G01X370693D02*
Y-666936D01*
G01X369933D02*
X371453D01*
G01X376300Y-664269D02*
X376553Y-664019D01*
X376743Y-663603D01*
X376870Y-663019D01*
X376743Y-662519D01*
X376490Y-662186D01*
X376046Y-661936D01*
X374336D01*
Y-666936D01*
X376426D01*
X376870Y-666603D01*
X377123Y-666103D01*
X377250Y-665519D01*
X377123Y-664936D01*
X376743Y-664436D01*
X376300Y-664269D01*
X374336D01*
G01X380893Y-667103D02*
X380766Y-667019D01*
Y-666853D01*
X380893Y-666769D01*
X381020Y-666853D01*
Y-667019D01*
X380893Y-667103D01*
G01Y-664853D02*
X380766Y-664769D01*
Y-664603D01*
X380893Y-664519D01*
X381020Y-664603D01*
Y-664769D01*
X380893Y-664853D01*
G01X404693Y-659436D02*
Y-684436D01*
G01Y-634436D02*
Y-659436D01*
G01X412706Y-687603D02*
X412813Y-687478D01*
X412893Y-687269D01*
X412946Y-686978D01*
X412893Y-686728D01*
X412786Y-686561D01*
X412600Y-686436D01*
X411880D01*
Y-688936D01*
X412760D01*
X412946Y-688769D01*
X413053Y-688519D01*
X413106Y-688228D01*
X413053Y-687936D01*
X412893Y-687686D01*
X412706Y-687603D01*
X411880D01*
G01X415173Y-688936D02*
Y-687269D01*
G01Y-687561D02*
X415066Y-687394D01*
X414906Y-687311D01*
X414720Y-687269D01*
X414533Y-687353D01*
X414373Y-687519D01*
X414266Y-687769D01*
X414213Y-688103D01*
X414266Y-688436D01*
X414373Y-688686D01*
X414533Y-688853D01*
X414720Y-688936D01*
X414906Y-688894D01*
X415066Y-688769D01*
X415173Y-688603D01*
G01X416493Y-688644D02*
X416626Y-688811D01*
X416813Y-688936D01*
X416973D01*
X417133Y-688853D01*
X417240Y-688728D01*
X417293Y-688561D01*
X417266Y-688311D01*
X417160Y-688186D01*
X416680Y-687936D01*
X416573Y-687644D01*
X416626Y-687436D01*
X416733Y-687311D01*
X416893Y-687269D01*
X417053Y-687311D01*
X417213Y-687436D01*
G01X418693Y-687811D02*
X419546D01*
X419466Y-687519D01*
X419333Y-687353D01*
X419146Y-687269D01*
X418960Y-687311D01*
X418800Y-687436D01*
X418693Y-687728D01*
X418640Y-687978D01*
Y-688228D01*
X418693Y-688478D01*
X418826Y-688728D01*
X418986Y-688894D01*
X419173Y-688936D01*
X419360Y-688853D01*
X419546Y-688603D01*
G01X420813Y-688936D02*
Y-686436D01*
G01Y-687686D02*
X420946Y-687436D01*
X421106Y-687311D01*
X421266Y-687269D01*
X421506Y-687353D01*
X421666Y-687519D01*
X421773Y-687811D01*
Y-688144D01*
X421720Y-688478D01*
X421613Y-688728D01*
X421426Y-688894D01*
X421266Y-688936D01*
X421106Y-688894D01*
X420946Y-688769D01*
X420813Y-688561D01*
G01X423493Y-688936D02*
X423333Y-688894D01*
X423173Y-688728D01*
X423066Y-688436D01*
X423013Y-688103D01*
X423066Y-687769D01*
X423173Y-687478D01*
X423333Y-687311D01*
X423493Y-687269D01*
X423653Y-687311D01*
X423813Y-687478D01*
X423920Y-687769D01*
X423946Y-688103D01*
X423920Y-688436D01*
X423813Y-688728D01*
X423653Y-688894D01*
X423493Y-688936D01*
G01X426173D02*
Y-687269D01*
G01Y-687561D02*
X426066Y-687394D01*
X425906Y-687311D01*
X425720Y-687269D01*
X425533Y-687353D01*
X425373Y-687519D01*
X425266Y-687769D01*
X425213Y-688103D01*
X425266Y-688436D01*
X425373Y-688686D01*
X425533Y-688853D01*
X425720Y-688936D01*
X425906Y-688894D01*
X426066Y-688769D01*
X426173Y-688603D01*
G01X427520Y-688936D02*
Y-687269D01*
G01Y-687603D02*
X427653Y-687436D01*
X427786Y-687311D01*
X427973Y-687269D01*
X428106Y-687311D01*
X428266Y-687436D01*
G01X430573Y-686436D02*
Y-688936D01*
G01Y-688561D02*
X430466Y-688769D01*
X430306Y-688894D01*
X430120Y-688936D01*
X429906Y-688853D01*
X429746Y-688644D01*
X429640Y-688394D01*
X429613Y-688103D01*
X429640Y-687811D01*
X429746Y-687561D01*
X429906Y-687353D01*
X430120Y-687269D01*
X430306Y-687311D01*
X430440Y-687394D01*
X430573Y-687561D01*
G01X433960Y-688936D02*
Y-686436D01*
X434626D01*
X434840Y-686561D01*
X434973Y-686728D01*
X435026Y-687061D01*
X434973Y-687394D01*
X434813Y-687603D01*
X434626Y-687728D01*
X433960D01*
G01X434626D02*
X435026Y-688936D01*
G01X436293Y-687811D02*
X437146D01*
X437066Y-687519D01*
X436933Y-687353D01*
X436746Y-687269D01*
X436560Y-687311D01*
X436400Y-687436D01*
X436293Y-687728D01*
X436240Y-687978D01*
Y-688228D01*
X436293Y-688478D01*
X436426Y-688728D01*
X436586Y-688894D01*
X436773Y-688936D01*
X436960Y-688853D01*
X437146Y-688603D01*
G01X438413Y-687269D02*
X438893Y-688936D01*
X439373Y-687269D01*
G01X441093Y-689019D02*
X441040Y-688978D01*
Y-688894D01*
X441093Y-688853D01*
X441146Y-688894D01*
Y-688978D01*
X441093Y-689019D01*
G01X443613Y-688936D02*
Y-686436D01*
X442626Y-688228D01*
X443960D01*
G01X444826Y-688936D02*
X445493Y-686436D01*
X446160Y-688936D01*
G01X445920Y-688061D02*
X445066D01*
G01X408593Y-661936D02*
Y-666936D01*
G01X407136Y-661936D02*
X410050D01*
G01X413693Y-666936D02*
X413313Y-666853D01*
X412933Y-666519D01*
X412680Y-665936D01*
X412553Y-665269D01*
X412680Y-664603D01*
X412933Y-664019D01*
X413313Y-663686D01*
X413693Y-663603D01*
X414073Y-663686D01*
X414453Y-664019D01*
X414706Y-664603D01*
X414770Y-665269D01*
X414706Y-665936D01*
X414453Y-666519D01*
X414073Y-666853D01*
X413693Y-666936D01*
G01X418793D02*
X418413Y-666853D01*
X418033Y-666519D01*
X417780Y-665936D01*
X417653Y-665269D01*
X417780Y-664603D01*
X418033Y-664019D01*
X418413Y-663686D01*
X418793Y-663603D01*
X419173Y-663686D01*
X419553Y-664019D01*
X419806Y-664603D01*
X419870Y-665269D01*
X419806Y-665936D01*
X419553Y-666519D01*
X419173Y-666853D01*
X418793Y-666936D01*
G01X423893D02*
Y-661936D01*
G01X428993Y-667103D02*
X428866Y-667019D01*
Y-666853D01*
X428993Y-666769D01*
X429120Y-666853D01*
Y-667019D01*
X428993Y-667103D01*
G01Y-664853D02*
X428866Y-664769D01*
Y-664603D01*
X428993Y-664519D01*
X429120Y-664603D01*
Y-664769D01*
X428993Y-664853D01*
G01X407326Y-641936D02*
Y-636936D01*
X408910D01*
X409416Y-637186D01*
X409733Y-637519D01*
X409860Y-638186D01*
X409733Y-638853D01*
X409353Y-639269D01*
X408910Y-639519D01*
X407326D01*
G01X408910D02*
X409860Y-641936D01*
G01X414960D02*
X412426D01*
Y-636936D01*
X414960D01*
G01X413946Y-639353D02*
X412426D01*
G01X417210Y-636936D02*
X418793Y-641936D01*
X420376Y-636936D01*
G01X423893Y-642103D02*
X423766Y-642019D01*
Y-641853D01*
X423893Y-641769D01*
X424020Y-641853D01*
Y-642019D01*
X423893Y-642103D01*
G01Y-639853D02*
X423766Y-639769D01*
Y-639603D01*
X423893Y-639519D01*
X424020Y-639603D01*
Y-639769D01*
X423893Y-639853D01*
G01X2010999Y-388000D02*
Y1475775D01*
X-407000D01*
Y-386798D01*
Y-755294D01*
Y-793716D01*
X-368578D01*
X1942346D01*
X2010999D01*
Y-725063D01*
Y-388000D01*
G01X-42602Y-671096D02*
X-41975Y-671621D01*
X-41270Y-671936D01*
X-40644D01*
X-40017Y-671621D01*
X-39547Y-671096D01*
X-39312Y-670361D01*
X-39469Y-669626D01*
X-39860Y-668996D01*
X-40565Y-668576D01*
X-41505Y-668366D01*
X-42054Y-667946D01*
X-42289Y-667211D01*
X-42132Y-666476D01*
X-41740Y-665951D01*
X-41192Y-665636D01*
X-40644D01*
X-40095Y-665846D01*
X-39625Y-666371D01*
G01X-36302Y-671936D02*
Y-665636D01*
G01X-33012D02*
Y-671936D01*
G01Y-668786D02*
X-36302D01*
G01X-29297Y-665636D02*
X-27417D01*
G01X-28357D02*
Y-671936D01*
G01X-29297D02*
X-27417D01*
G01X-20490D02*
X-23624D01*
Y-665636D01*
X-20490D01*
G01X-21744Y-668681D02*
X-23624D01*
G01X-17559Y-671936D02*
Y-665636D01*
X-13955Y-671936D01*
Y-665636D01*
G01X-9614Y-673091D02*
X-9300Y-671726D01*
G01X-3157Y-665636D02*
Y-671936D01*
G01X-4959Y-665636D02*
X-1355D01*
G01X1185Y-671936D02*
X3143Y-665636D01*
X5101Y-671936D01*
G01X4396Y-669731D02*
X1890D01*
G01X8503Y-665636D02*
X10383D01*
G01X9443D02*
Y-671936D01*
G01X8503D02*
X10383D01*
G01X13393Y-665636D02*
X14490Y-671936D01*
X15743Y-665636D01*
X16996Y-671936D01*
X18093Y-665636D01*
G01X20085Y-671936D02*
X22043Y-665636D01*
X24001Y-671936D01*
G01X23296Y-669731D02*
X20790D01*
G01X26541Y-671936D02*
Y-665636D01*
X30145Y-671936D01*
Y-665636D01*
G01X39376Y-671936D02*
Y-665636D01*
X41335D01*
X41961Y-665951D01*
X42353Y-666371D01*
X42510Y-667211D01*
X42353Y-668051D01*
X41883Y-668576D01*
X41335Y-668891D01*
X39376D01*
G01X41335D02*
X42510Y-671936D01*
G01X47243Y-672146D02*
X47086Y-672041D01*
Y-671831D01*
X47243Y-671726D01*
X47400Y-671831D01*
Y-672041D01*
X47243Y-672146D01*
G01X53543Y-671936D02*
X52916Y-671831D01*
X52368Y-671411D01*
X51898Y-670781D01*
X51585Y-670046D01*
X51428Y-669206D01*
Y-668366D01*
X51585Y-667526D01*
X51898Y-666791D01*
X52368Y-666161D01*
X52916Y-665741D01*
X53543Y-665636D01*
X54170Y-665741D01*
X54718Y-666161D01*
X55188Y-666791D01*
X55501Y-667526D01*
X55658Y-668366D01*
Y-669206D01*
X55501Y-670046D01*
X55188Y-670781D01*
X54718Y-671411D01*
X54170Y-671831D01*
X53543Y-671936D01*
G01X59843Y-672146D02*
X59686Y-672041D01*
Y-671831D01*
X59843Y-671726D01*
X60000Y-671831D01*
Y-672041D01*
X59843Y-672146D01*
G01X67866Y-666161D02*
X67396Y-665846D01*
X66848Y-665636D01*
X66221D01*
X65516Y-665951D01*
X64968Y-666476D01*
X64576Y-667106D01*
X64263Y-668156D01*
X64185Y-669101D01*
X64341Y-670046D01*
X64576Y-670676D01*
X65046Y-671306D01*
X65595Y-671726D01*
X66143Y-671936D01*
X66691D01*
X67240Y-671726D01*
X67710Y-671411D01*
X68101Y-670991D01*
G01X72443Y-672146D02*
X72286Y-672041D01*
Y-671831D01*
X72443Y-671726D01*
X72600Y-671831D01*
Y-672041D01*
X72443Y-672146D01*
G01X-42680Y-661936D02*
Y-655636D01*
G01X-39704D02*
X-42680Y-659521D01*
G01X-39234Y-661936D02*
X-41349Y-657736D01*
G01X-36380Y-655636D02*
Y-660151D01*
X-36067Y-661096D01*
X-35440Y-661726D01*
X-34657Y-661936D01*
X-33874Y-661726D01*
X-33247Y-661096D01*
X-32934Y-660151D01*
Y-655636D01*
G01X-26790Y-661936D02*
X-29924D01*
Y-655636D01*
X-26790D01*
G01X-28044Y-658681D02*
X-29924D01*
G01X-22997Y-655636D02*
X-21117D01*
G01X-22057D02*
Y-661936D01*
G01X-22997D02*
X-21117D01*
G01X-11102Y-661096D02*
X-10475Y-661621D01*
X-9770Y-661936D01*
X-9144D01*
X-8517Y-661621D01*
X-8047Y-661096D01*
X-7812Y-660361D01*
X-7969Y-659626D01*
X-8360Y-658996D01*
X-9065Y-658576D01*
X-10005Y-658366D01*
X-10554Y-657946D01*
X-10789Y-657211D01*
X-10632Y-656476D01*
X-10240Y-655951D01*
X-9692Y-655636D01*
X-9144D01*
X-8595Y-655846D01*
X-8125Y-656371D01*
G01X-4802Y-661936D02*
Y-655636D01*
G01X-1512D02*
Y-661936D01*
G01Y-658786D02*
X-4802D01*
G01X1185Y-661936D02*
X3143Y-655636D01*
X5101Y-661936D01*
G01X4396Y-659731D02*
X1890D01*
G01X7641Y-661936D02*
Y-655636D01*
X11245Y-661936D01*
Y-655636D01*
G01X20398Y-661936D02*
Y-655636D01*
G01X23688D02*
Y-661936D01*
G01Y-658786D02*
X20398D01*
G01X26698Y-661096D02*
X27325Y-661621D01*
X28030Y-661936D01*
X28656D01*
X29283Y-661621D01*
X29753Y-661096D01*
X29988Y-660361D01*
X29831Y-659626D01*
X29440Y-658996D01*
X28735Y-658576D01*
X27795Y-658366D01*
X27246Y-657946D01*
X27011Y-657211D01*
X27168Y-656476D01*
X27560Y-655951D01*
X28108Y-655636D01*
X28656D01*
X29205Y-655846D01*
X29675Y-656371D01*
G01X33703Y-655636D02*
X35583D01*
G01X34643D02*
Y-661936D01*
G01X33703D02*
X35583D01*
G01X38985D02*
X40943Y-655636D01*
X42901Y-661936D01*
G01X42196Y-659731D02*
X39690D01*
G01X45441Y-661936D02*
Y-655636D01*
X49045Y-661936D01*
Y-655636D01*
G01X54013Y-658786D02*
X55580D01*
Y-660676D01*
X55110Y-661306D01*
X54561Y-661726D01*
X53778Y-661936D01*
X52995Y-661726D01*
X52446Y-661306D01*
X51976Y-660676D01*
X51663Y-659941D01*
X51506Y-659101D01*
Y-658366D01*
X51663Y-657736D01*
X51976Y-657001D01*
X52446Y-656371D01*
X52916Y-655951D01*
X53543Y-655636D01*
X54091D01*
X54718Y-655846D01*
X55188Y-656266D01*
G01X59686Y-663091D02*
X60000Y-661726D01*
G01X66143Y-655636D02*
Y-661936D01*
G01X64341Y-655636D02*
X67945D01*
G01X70485Y-661936D02*
X72443Y-655636D01*
X74401Y-661936D01*
G01X73696Y-659731D02*
X71190D01*
G01X78743Y-661936D02*
X78116Y-661831D01*
X77568Y-661411D01*
X77098Y-660781D01*
X76785Y-660046D01*
X76628Y-659206D01*
Y-658366D01*
X76785Y-657526D01*
X77098Y-656791D01*
X77568Y-656161D01*
X78116Y-655741D01*
X78743Y-655636D01*
X79370Y-655741D01*
X79918Y-656161D01*
X80388Y-656791D01*
X80701Y-657526D01*
X80858Y-658366D01*
Y-659206D01*
X80701Y-660046D01*
X80388Y-660781D01*
X79918Y-661411D01*
X79370Y-661831D01*
X78743Y-661936D01*
G01X91343D02*
Y-659101D01*
X89776Y-655636D01*
G01X92910D02*
X91343Y-659101D01*
G01X95920Y-655636D02*
Y-660151D01*
X96233Y-661096D01*
X96860Y-661726D01*
X97643Y-661936D01*
X98426Y-661726D01*
X99053Y-661096D01*
X99366Y-660151D01*
Y-655636D01*
G01X101985Y-661936D02*
X103943Y-655636D01*
X105901Y-661936D01*
G01X105196Y-659731D02*
X102690D01*
G01X108441Y-661936D02*
Y-655636D01*
X112045Y-661936D01*
Y-655636D01*
G01X-42759Y-651936D02*
Y-645636D01*
X-39155Y-651936D01*
Y-645636D01*
G01X-34657Y-651936D02*
X-35284Y-651831D01*
X-35832Y-651411D01*
X-36302Y-650781D01*
X-36615Y-650046D01*
X-36772Y-649206D01*
Y-648366D01*
X-36615Y-647526D01*
X-36302Y-646791D01*
X-35832Y-646161D01*
X-35284Y-645741D01*
X-34657Y-645636D01*
X-34030Y-645741D01*
X-33482Y-646161D01*
X-33012Y-646791D01*
X-32699Y-647526D01*
X-32542Y-648366D01*
Y-649206D01*
X-32699Y-650046D01*
X-33012Y-650781D01*
X-33482Y-651411D01*
X-34030Y-651831D01*
X-34657Y-651936D01*
G01X-28357Y-652146D02*
X-28514Y-652041D01*
Y-651831D01*
X-28357Y-651726D01*
X-28200Y-651831D01*
Y-652041D01*
X-28357Y-652146D01*
G01X-22057Y-651936D02*
Y-645636D01*
X-22997Y-646896D01*
G01Y-651936D02*
X-21117D01*
G01X-15757D02*
X-15209Y-651831D01*
X-14582Y-651516D01*
X-14190Y-650991D01*
X-14034Y-650256D01*
X-14190Y-649521D01*
X-14660Y-648891D01*
X-15365Y-648576D01*
X-16149D01*
X-16619Y-648366D01*
X-17010Y-647841D01*
X-17167Y-647106D01*
X-16932Y-646371D01*
X-16384Y-645846D01*
X-15757Y-645636D01*
X-15130Y-645846D01*
X-14582Y-646371D01*
X-14347Y-647106D01*
X-14504Y-647841D01*
X-14895Y-648366D01*
X-15365Y-648576D01*
X-16149D01*
X-16854Y-648891D01*
X-17324Y-649521D01*
X-17480Y-650256D01*
X-17324Y-650991D01*
X-16932Y-651516D01*
X-16305Y-651831D01*
X-15757Y-651936D01*
G01X-9457D02*
X-8909Y-651831D01*
X-8282Y-651516D01*
X-7890Y-650991D01*
X-7734Y-650256D01*
X-7890Y-649521D01*
X-8360Y-648891D01*
X-9065Y-648576D01*
X-9849D01*
X-10319Y-648366D01*
X-10710Y-647841D01*
X-10867Y-647106D01*
X-10632Y-646371D01*
X-10084Y-645846D01*
X-9457Y-645636D01*
X-8830Y-645846D01*
X-8282Y-646371D01*
X-8047Y-647106D01*
X-8204Y-647841D01*
X-8595Y-648366D01*
X-9065Y-648576D01*
X-9849D01*
X-10554Y-648891D01*
X-11024Y-649521D01*
X-11180Y-650256D01*
X-11024Y-650991D01*
X-10632Y-651516D01*
X-10005Y-651831D01*
X-9457Y-651936D01*
G01X-3314Y-653091D02*
X-3000Y-651726D01*
G01X793Y-645636D02*
X1890Y-651936D01*
X3143Y-645636D01*
X4396Y-651936D01*
X5493Y-645636D01*
G01X11010Y-651936D02*
X7876D01*
Y-645636D01*
X11010D01*
G01X9756Y-648681D02*
X7876D01*
G01X13941Y-651936D02*
Y-645636D01*
X17545Y-651936D01*
Y-645636D01*
G01X26698Y-651936D02*
Y-645636D01*
G01X29988D02*
Y-651936D01*
G01Y-648786D02*
X26698D01*
G01X32293Y-645636D02*
X33390Y-651936D01*
X34643Y-645636D01*
X35896Y-651936D01*
X36993Y-645636D01*
G01X38985Y-651936D02*
X40943Y-645636D01*
X42901Y-651936D01*
G01X42196Y-649731D02*
X39690D01*
G01X52055Y-646686D02*
X52525Y-646056D01*
X53073Y-645741D01*
X53700Y-645636D01*
X54483Y-645846D01*
X55031Y-646371D01*
X55188Y-647001D01*
X55110Y-647631D01*
X54796Y-648156D01*
X53230Y-649206D01*
X52525Y-649941D01*
X52055Y-650991D01*
X51898Y-651936D01*
X55188D01*
G01X58041D02*
Y-645636D01*
X61645Y-651936D01*
Y-645636D01*
G01X64420Y-651936D02*
Y-645636D01*
X65986D01*
X66613Y-645951D01*
X67083Y-646371D01*
X67475Y-647001D01*
X67788Y-647736D01*
X67866Y-648786D01*
X67788Y-649836D01*
X67475Y-650571D01*
X67083Y-651201D01*
X66613Y-651621D01*
X65986Y-651936D01*
X64420D01*
G01X77176D02*
Y-645636D01*
X79135D01*
X79761Y-645951D01*
X80153Y-646371D01*
X80310Y-647211D01*
X80153Y-648051D01*
X79683Y-648576D01*
X79135Y-648891D01*
X77176D01*
G01X79135D02*
X80310Y-651936D01*
G01X83320D02*
Y-645636D01*
X84886D01*
X85513Y-645951D01*
X85983Y-646371D01*
X86375Y-647001D01*
X86688Y-647736D01*
X86766Y-648786D01*
X86688Y-649836D01*
X86375Y-650571D01*
X85983Y-651201D01*
X85513Y-651621D01*
X84886Y-651936D01*
X83320D01*
G01X91343Y-652146D02*
X91186Y-652041D01*
Y-651831D01*
X91343Y-651726D01*
X91500Y-651831D01*
Y-652041D01*
X91343Y-652146D01*
G01X-18657Y-639236D02*
X-21177Y-638819D01*
X-23382Y-637153D01*
X-25272Y-634653D01*
X-26532Y-631736D01*
X-27162Y-628403D01*
Y-625069D01*
X-26532Y-621736D01*
X-25272Y-618819D01*
X-23382Y-616320D01*
X-21177Y-614653D01*
X-18657Y-614236D01*
X-16137Y-614653D01*
X-13932Y-616320D01*
X-12042Y-618819D01*
X-10782Y-621736D01*
X-10152Y-625069D01*
Y-628403D01*
X-10782Y-631736D01*
X-12042Y-634653D01*
X-13932Y-637153D01*
X-16137Y-638819D01*
X-18657Y-639236D01*
G01X-16137Y-632569D02*
X-12357Y-639236D01*
G01X1188Y-622570D02*
Y-634236D01*
X2448Y-637153D01*
X4338Y-638819D01*
X6543Y-639236D01*
X8748Y-638819D01*
X10638Y-637153D01*
X11898Y-634236D01*
G01Y-639236D02*
Y-622570D01*
G01X37413Y-639236D02*
Y-622570D01*
G01Y-625486D02*
X36153Y-623820D01*
X34263Y-622986D01*
X32058Y-622570D01*
X29853Y-623403D01*
X27963Y-625069D01*
X26703Y-627570D01*
X26073Y-630903D01*
X26703Y-634236D01*
X27963Y-636737D01*
X29853Y-638403D01*
X32058Y-639236D01*
X34263Y-638819D01*
X36153Y-637570D01*
X37413Y-635903D01*
G01X51588Y-639236D02*
Y-622570D01*
G01Y-626736D02*
X52848Y-624653D01*
X54738Y-622986D01*
X57258Y-622570D01*
X59463Y-622986D01*
X61353Y-624653D01*
X62298Y-627570D01*
Y-639236D01*
G01X82143Y-614236D02*
Y-639236D01*
G01X77733Y-622570D02*
X86553D01*
G01X113013Y-639236D02*
Y-622570D01*
G01Y-625486D02*
X111753Y-623820D01*
X109863Y-622986D01*
X107658Y-622570D01*
X105453Y-623403D01*
X103563Y-625069D01*
X102303Y-627570D01*
X101673Y-630903D01*
X102303Y-634236D01*
X103563Y-636737D01*
X105453Y-638403D01*
X107658Y-639236D01*
X109863Y-638819D01*
X111753Y-637570D01*
X113013Y-635903D01*
G01X152693Y-618936D02*
Y-626936D01*
X156693D01*
G01X164493D02*
Y-621603D01*
G01Y-622536D02*
X164093Y-622003D01*
X163493Y-621736D01*
X162793Y-621603D01*
X162093Y-621869D01*
X161493Y-622403D01*
X161093Y-623203D01*
X160893Y-624269D01*
X161093Y-625336D01*
X161493Y-626136D01*
X162093Y-626669D01*
X162793Y-626936D01*
X163493Y-626803D01*
X164093Y-626403D01*
X164493Y-625870D01*
G01X168593Y-629336D02*
X169193Y-629603D01*
X169993Y-629336D01*
X170493Y-628803D01*
X170893Y-628136D01*
X171493Y-626003D01*
X172793Y-621603D01*
G01X169593D02*
X171493Y-626003D01*
G01X177193Y-623336D02*
X180393D01*
X180093Y-622403D01*
X179593Y-621869D01*
X178893Y-621603D01*
X178193Y-621736D01*
X177593Y-622136D01*
X177193Y-623069D01*
X176993Y-623870D01*
Y-624669D01*
X177193Y-625469D01*
X177693Y-626269D01*
X178293Y-626803D01*
X178993Y-626936D01*
X179693Y-626669D01*
X180393Y-625870D01*
G01X185293Y-626936D02*
Y-621603D01*
G01Y-622669D02*
X185793Y-622136D01*
X186293Y-621736D01*
X186993Y-621603D01*
X187493Y-621736D01*
X188093Y-622136D01*
G01X173993Y-676936D02*
Y-668936D01*
G01X177793D02*
X173993Y-673870D01*
G01X178393Y-676936D02*
X175693Y-671603D01*
G01X185993Y-676936D02*
Y-671603D01*
G01Y-672536D02*
X185593Y-672003D01*
X184993Y-671736D01*
X184293Y-671603D01*
X183593Y-671869D01*
X182993Y-672403D01*
X182593Y-673203D01*
X182393Y-674269D01*
X182593Y-675336D01*
X182993Y-676136D01*
X183593Y-676669D01*
X184293Y-676936D01*
X184993Y-676803D01*
X185593Y-676403D01*
X185993Y-675870D01*
G01X192193Y-671603D02*
Y-676936D01*
G01Y-669469D02*
X191993Y-669336D01*
Y-669069D01*
X192193Y-668936D01*
X192393Y-669069D01*
Y-669336D01*
X192193Y-669469D01*
G01X181193Y-643936D02*
X183693Y-651936D01*
X186193Y-643936D01*
G01X193893Y-644603D02*
X193293Y-644203D01*
X192593Y-643936D01*
X191793D01*
X190893Y-644336D01*
X190193Y-645003D01*
X189693Y-645803D01*
X189293Y-647136D01*
X189193Y-648336D01*
X189393Y-649536D01*
X189693Y-650336D01*
X190293Y-651136D01*
X190993Y-651669D01*
X191693Y-651936D01*
X192393D01*
X193093Y-651669D01*
X193693Y-651269D01*
X194193Y-650736D01*
G01X201893Y-644603D02*
X201293Y-644203D01*
X200593Y-643936D01*
X199793D01*
X198893Y-644336D01*
X198193Y-645003D01*
X197693Y-645803D01*
X197293Y-647136D01*
X197193Y-648336D01*
X197393Y-649536D01*
X197693Y-650336D01*
X198293Y-651136D01*
X198993Y-651669D01*
X199693Y-651936D01*
X200393D01*
X201093Y-651669D01*
X201693Y-651269D01*
X202193Y-650736D01*
G01X204293Y-623603D02*
X204993Y-622669D01*
X205593Y-622136D01*
X206393Y-621869D01*
X207093Y-622136D01*
X207593Y-622669D01*
X207993Y-623469D01*
X208093Y-624403D01*
X207993Y-625203D01*
X207593Y-626003D01*
X206993Y-626669D01*
X206293Y-626936D01*
X205493Y-626669D01*
X204793Y-625870D01*
X204393Y-624669D01*
X204293Y-623336D01*
X204493Y-621603D01*
X204793Y-620669D01*
X205293Y-619736D01*
X205993Y-619069D01*
X206693Y-618936D01*
X207393Y-619203D01*
X207893Y-619869D01*
G01X279293Y-670269D02*
X279893Y-669469D01*
X280593Y-669069D01*
X281393Y-668936D01*
X282393Y-669203D01*
X283093Y-669869D01*
X283293Y-670669D01*
X283193Y-671470D01*
X282793Y-672136D01*
X280793Y-673469D01*
X279893Y-674403D01*
X279293Y-675736D01*
X279093Y-676936D01*
X283293D01*
G01X289193Y-668936D02*
X288393Y-669203D01*
X287793Y-669869D01*
X287393Y-670669D01*
X287093Y-671736D01*
X286993Y-672936D01*
X287093Y-674136D01*
X287393Y-675203D01*
X287793Y-676003D01*
X288393Y-676669D01*
X289193Y-676936D01*
X289993Y-676669D01*
X290593Y-676003D01*
X290993Y-675203D01*
X291293Y-674136D01*
X291393Y-672936D01*
X291293Y-671736D01*
X290993Y-670669D01*
X290593Y-669869D01*
X289993Y-669203D01*
X289193Y-668936D01*
G01X295293Y-670269D02*
X295893Y-669469D01*
X296593Y-669069D01*
X297393Y-668936D01*
X298393Y-669203D01*
X299093Y-669869D01*
X299293Y-670669D01*
X299193Y-671470D01*
X298793Y-672136D01*
X296793Y-673469D01*
X295893Y-674403D01*
X295293Y-675736D01*
X295093Y-676936D01*
X299293D01*
G01X303293Y-670269D02*
X303893Y-669469D01*
X304593Y-669069D01*
X305393Y-668936D01*
X306393Y-669203D01*
X307093Y-669869D01*
X307293Y-670669D01*
X307193Y-671470D01*
X306793Y-672136D01*
X304793Y-673469D01*
X303893Y-674403D01*
X303293Y-675736D01*
X303093Y-676936D01*
X307293D01*
G01X311393Y-677203D02*
X314993Y-668936D01*
G01X321193Y-676936D02*
Y-668936D01*
X319993Y-670536D01*
G01Y-676936D02*
X322393D01*
G01X327293Y-670269D02*
X327893Y-669469D01*
X328593Y-669069D01*
X329393Y-668936D01*
X330393Y-669203D01*
X331093Y-669869D01*
X331293Y-670669D01*
X331193Y-671470D01*
X330793Y-672136D01*
X328793Y-673469D01*
X327893Y-674403D01*
X327293Y-675736D01*
X327093Y-676936D01*
X331293D01*
G01X335393Y-677203D02*
X338993Y-668936D01*
G01X345193D02*
X344393Y-669203D01*
X343793Y-669869D01*
X343393Y-670669D01*
X343093Y-671736D01*
X342993Y-672936D01*
X343093Y-674136D01*
X343393Y-675203D01*
X343793Y-676003D01*
X344393Y-676669D01*
X345193Y-676936D01*
X345993Y-676669D01*
X346593Y-676003D01*
X346993Y-675203D01*
X347293Y-674136D01*
X347393Y-672936D01*
X347293Y-671736D01*
X346993Y-670669D01*
X346593Y-669869D01*
X345993Y-669203D01*
X345193Y-668936D01*
G01X351493Y-676003D02*
X352193Y-676669D01*
X352993Y-676936D01*
X353793Y-676669D01*
X354493Y-675870D01*
X354993Y-674669D01*
X355193Y-673469D01*
Y-672003D01*
X354993Y-670803D01*
X354493Y-669736D01*
X353893Y-669203D01*
X353193Y-668936D01*
X352393Y-669203D01*
X351793Y-669736D01*
X351393Y-670536D01*
X351193Y-671603D01*
X351393Y-672536D01*
X351893Y-673469D01*
X352493Y-674003D01*
X353193Y-674136D01*
X353993Y-673870D01*
X354593Y-673203D01*
X355193Y-672003D01*
G01X278993Y-651936D02*
Y-643936D01*
X280993D01*
X281793Y-644336D01*
X282393Y-644869D01*
X282893Y-645669D01*
X283293Y-646603D01*
X283393Y-647936D01*
X283293Y-649269D01*
X282893Y-650203D01*
X282393Y-651003D01*
X281793Y-651536D01*
X280993Y-651936D01*
X278993D01*
G01X286693D02*
X289193Y-643936D01*
X291693Y-651936D01*
G01X290793Y-649136D02*
X287593D01*
G01X297193Y-643936D02*
X296393Y-644203D01*
X295793Y-644869D01*
X295393Y-645669D01*
X295093Y-646736D01*
X294993Y-647936D01*
X295093Y-649136D01*
X295393Y-650203D01*
X295793Y-651003D01*
X296393Y-651669D01*
X297193Y-651936D01*
X297993Y-651669D01*
X298593Y-651003D01*
X298993Y-650203D01*
X299293Y-649136D01*
X299393Y-647936D01*
X299293Y-646736D01*
X298993Y-645669D01*
X298593Y-644869D01*
X297993Y-644203D01*
X297193Y-643936D01*
G01X303293Y-651936D02*
Y-643936D01*
X307093D01*
G01X305693Y-647803D02*
X303293D01*
G01X313193Y-643936D02*
X312393Y-644203D01*
X311793Y-644869D01*
X311393Y-645669D01*
X311093Y-646736D01*
X310993Y-647936D01*
X311093Y-649136D01*
X311393Y-650203D01*
X311793Y-651003D01*
X312393Y-651669D01*
X313193Y-651936D01*
X313993Y-651669D01*
X314593Y-651003D01*
X314993Y-650203D01*
X315293Y-649136D01*
X315393Y-647936D01*
X315293Y-646736D01*
X314993Y-645669D01*
X314593Y-644869D01*
X313993Y-644203D01*
X313193Y-643936D01*
G01X321193D02*
Y-651936D01*
G01X318893Y-643936D02*
X323493D01*
G01X326593Y-651936D02*
Y-643936D01*
X329193Y-650603D01*
X331793Y-643936D01*
Y-651936D01*
G01X334993D02*
Y-643936D01*
X336993D01*
X337793Y-644336D01*
X338393Y-644869D01*
X338893Y-645669D01*
X339293Y-646603D01*
X339393Y-647936D01*
X339293Y-649269D01*
X338893Y-650203D01*
X338393Y-651003D01*
X337793Y-651536D01*
X336993Y-651936D01*
X334993D01*
G01X347393Y-644603D02*
X346793Y-644203D01*
X346093Y-643936D01*
X345293D01*
X344393Y-644336D01*
X343693Y-645003D01*
X343193Y-645803D01*
X342793Y-647136D01*
X342693Y-648336D01*
X342893Y-649536D01*
X343193Y-650336D01*
X343793Y-651136D01*
X344493Y-651669D01*
X345193Y-651936D01*
X345893D01*
X346593Y-651669D01*
X347193Y-651269D01*
X347693Y-650736D01*
G01X350993Y-651936D02*
Y-643936D01*
X352993D01*
X353793Y-644336D01*
X354393Y-644869D01*
X354893Y-645669D01*
X355293Y-646603D01*
X355393Y-647936D01*
X355293Y-649269D01*
X354893Y-650203D01*
X354393Y-651003D01*
X353793Y-651536D01*
X352993Y-651936D01*
X350993D01*
G01X361193Y-643936D02*
X360393Y-644203D01*
X359793Y-644869D01*
X359393Y-645669D01*
X359093Y-646736D01*
X358993Y-647936D01*
X359093Y-649136D01*
X359393Y-650203D01*
X359793Y-651003D01*
X360393Y-651669D01*
X361193Y-651936D01*
X361993Y-651669D01*
X362593Y-651003D01*
X362993Y-650203D01*
X363293Y-649136D01*
X363393Y-647936D01*
X363293Y-646736D01*
X362993Y-645669D01*
X362593Y-644869D01*
X361993Y-644203D01*
X361193Y-643936D01*
G01X298418Y-624819D02*
Y-618519D01*
X301394D01*
G01X300298Y-621564D02*
X298418D01*
G01X306206Y-618519D02*
X305579Y-618729D01*
X305109Y-619254D01*
X304796Y-619884D01*
X304561Y-620724D01*
X304483Y-621669D01*
X304561Y-622614D01*
X304796Y-623454D01*
X305109Y-624084D01*
X305579Y-624609D01*
X306206Y-624819D01*
X306833Y-624609D01*
X307303Y-624084D01*
X307616Y-623454D01*
X307851Y-622614D01*
X307929Y-621669D01*
X307851Y-620724D01*
X307616Y-619884D01*
X307303Y-619254D01*
X306833Y-618729D01*
X306206Y-618519D01*
G01X312506D02*
Y-624819D01*
G01X310704Y-618519D02*
X314308D01*
G01X316456Y-626919D02*
X321156D01*
G01X323069Y-624819D02*
Y-618519D01*
X325106Y-623769D01*
X327143Y-618519D01*
Y-624819D01*
G01X332816D02*
Y-620619D01*
G01Y-621354D02*
X332503Y-620934D01*
X332033Y-620724D01*
X331484Y-620619D01*
X330936Y-620829D01*
X330466Y-621249D01*
X330153Y-621879D01*
X329996Y-622719D01*
X330153Y-623559D01*
X330466Y-624189D01*
X330936Y-624609D01*
X331484Y-624819D01*
X332033Y-624714D01*
X332503Y-624399D01*
X332816Y-623979D01*
G01X336374Y-624819D02*
Y-620619D01*
G01Y-621669D02*
X336688Y-621144D01*
X337158Y-620724D01*
X337784Y-620619D01*
X338333Y-620724D01*
X338803Y-621144D01*
X339038Y-621879D01*
Y-624819D01*
G01X345416D02*
Y-620619D01*
G01Y-621354D02*
X345103Y-620934D01*
X344633Y-620724D01*
X344084Y-620619D01*
X343536Y-620829D01*
X343066Y-621249D01*
X342753Y-621879D01*
X342596Y-622719D01*
X342753Y-623559D01*
X343066Y-624189D01*
X343536Y-624609D01*
X344084Y-624819D01*
X344633Y-624714D01*
X345103Y-624399D01*
X345416Y-623979D01*
G01X349209Y-626394D02*
X349758Y-626814D01*
X350384Y-626919D01*
X350933Y-626814D01*
X351403Y-626289D01*
X351716Y-625554D01*
Y-620619D01*
G01Y-621459D02*
X351403Y-621039D01*
X350933Y-620724D01*
X350384Y-620619D01*
X349758Y-620829D01*
X349366Y-621249D01*
X349053Y-621984D01*
X348896Y-622719D01*
X348974Y-623349D01*
X349288Y-624084D01*
X349758Y-624609D01*
X350384Y-624819D01*
X350854Y-624714D01*
X351403Y-624294D01*
X351716Y-623874D01*
G01X355431Y-621984D02*
X357938D01*
X357703Y-621249D01*
X357311Y-620829D01*
X356763Y-620619D01*
X356214Y-620724D01*
X355744Y-621039D01*
X355431Y-621774D01*
X355274Y-622404D01*
Y-623034D01*
X355431Y-623664D01*
X355823Y-624294D01*
X356293Y-624714D01*
X356841Y-624819D01*
X357389Y-624609D01*
X357938Y-623979D01*
G01X360556Y-624819D02*
Y-620619D01*
G01Y-621774D02*
X360791Y-621249D01*
X361183Y-620829D01*
X361731Y-620619D01*
X362279Y-620829D01*
X362671Y-621249D01*
X362906Y-621774D01*
Y-624819D01*
G01Y-621774D02*
X363141Y-621249D01*
X363533Y-620829D01*
X364081Y-620619D01*
X364629Y-620829D01*
X365021Y-621249D01*
X365256Y-621879D01*
Y-624819D01*
G01X368031Y-621984D02*
X370538D01*
X370303Y-621249D01*
X369911Y-620829D01*
X369363Y-620619D01*
X368814Y-620724D01*
X368344Y-621039D01*
X368031Y-621774D01*
X367874Y-622404D01*
Y-623034D01*
X368031Y-623664D01*
X368423Y-624294D01*
X368893Y-624714D01*
X369441Y-624819D01*
X369989Y-624609D01*
X370538Y-623979D01*
G01X374174Y-624819D02*
Y-620619D01*
G01Y-621669D02*
X374488Y-621144D01*
X374958Y-620724D01*
X375584Y-620619D01*
X376133Y-620724D01*
X376603Y-621144D01*
X376838Y-621879D01*
Y-624819D01*
G01X381806Y-618519D02*
Y-624819D01*
G01X380709Y-620619D02*
X382903D01*
G01X385756Y-626919D02*
X390456D01*
G01X395033Y-621459D02*
X395346Y-621144D01*
X395581Y-620619D01*
X395738Y-619884D01*
X395581Y-619254D01*
X395268Y-618834D01*
X394719Y-618519D01*
X392604D01*
Y-624819D01*
X395189D01*
X395738Y-624399D01*
X396051Y-623769D01*
X396208Y-623034D01*
X396051Y-622299D01*
X395581Y-621669D01*
X395033Y-621459D01*
X392604D01*
G01X398983Y-624819D02*
Y-618519D01*
X400549D01*
X401176Y-618834D01*
X401646Y-619254D01*
X402038Y-619884D01*
X402351Y-620619D01*
X402429Y-621669D01*
X402351Y-622719D01*
X402038Y-623454D01*
X401646Y-624084D01*
X401176Y-624504D01*
X400549Y-624819D01*
X398983D01*
G01X367693Y-679936D02*
Y-671936D01*
X366493Y-673536D01*
G01Y-679936D02*
X368893D01*
G01X373793Y-676603D02*
X374493Y-675669D01*
X375093Y-675136D01*
X375893Y-674869D01*
X376593Y-675136D01*
X377093Y-675669D01*
X377493Y-676469D01*
X377593Y-677403D01*
X377493Y-678203D01*
X377093Y-679003D01*
X376493Y-679669D01*
X375793Y-679936D01*
X374993Y-679669D01*
X374293Y-678870D01*
X373893Y-677669D01*
X373793Y-676336D01*
X373993Y-674603D01*
X374293Y-673669D01*
X374793Y-672736D01*
X375493Y-672069D01*
X376193Y-671936D01*
X376893Y-672203D01*
X377393Y-672869D01*
G01X383693Y-680203D02*
X383493Y-680069D01*
Y-679803D01*
X383693Y-679669D01*
X383893Y-679803D01*
Y-680069D01*
X383693Y-680203D01*
G01X389793Y-676603D02*
X390493Y-675669D01*
X391093Y-675136D01*
X391893Y-674869D01*
X392593Y-675136D01*
X393093Y-675669D01*
X393493Y-676469D01*
X393593Y-677403D01*
X393493Y-678203D01*
X393093Y-679003D01*
X392493Y-679669D01*
X391793Y-679936D01*
X390993Y-679669D01*
X390293Y-678870D01*
X389893Y-677669D01*
X389793Y-676336D01*
X389993Y-674603D01*
X390293Y-673669D01*
X390793Y-672736D01*
X391493Y-672069D01*
X392193Y-671936D01*
X392893Y-672203D01*
X393393Y-672869D01*
G01X412693Y-679936D02*
Y-671936D01*
X411493Y-673536D01*
G01Y-679936D02*
X413893D01*
G01X420493D02*
X420693Y-678203D01*
X420993Y-676736D01*
X421393Y-675403D01*
X421893Y-673936D01*
X422693Y-671936D01*
X418693D01*
G01X428693Y-680203D02*
X428493Y-680069D01*
Y-679803D01*
X428693Y-679669D01*
X428893Y-679803D01*
Y-680069D01*
X428693Y-680203D01*
G01X434793Y-673269D02*
X435393Y-672469D01*
X436093Y-672069D01*
X436893Y-671936D01*
X437893Y-672203D01*
X438593Y-672869D01*
X438793Y-673669D01*
X438693Y-674470D01*
X438293Y-675136D01*
X436293Y-676469D01*
X435393Y-677403D01*
X434793Y-678736D01*
X434593Y-679936D01*
X438793D01*
G01X432493Y-654936D02*
Y-646936D01*
X434493D01*
X435293Y-647336D01*
X435893Y-647869D01*
X436393Y-648669D01*
X436793Y-649603D01*
X436893Y-650936D01*
X436793Y-652269D01*
X436393Y-653203D01*
X435893Y-654003D01*
X435293Y-654536D01*
X434493Y-654936D01*
X432493D01*
M02*
